FILE_TYPE = MACRO_DRAWING;
SET COLOR_WIRE YELLOW;
SET COLOR_PROP MONO;
SET COLOR_DOT WHITE;
SET COLOR_ARC YELLOW;
SET COLOR_BODY GREEN;
SET COLOR_NOTE MONO;
SET PROP_DISPLAY VALUE;
SET PAGE_NUMBER P33;
FORCEADD OFFPAGE..1
(-6450 2600);
FORCEPROP 2 LAST $XR0 67 
J 0
(-6701 2600);
DISPLAY 0.638298 (-6701 2600);
PAINT MONO (-6701 2600);
FORCEPROP 2 LAST CDS_LIB mstr_standard
J 0
(-6450 2600);
PAINT MONO (-6450 2600);
DISPLAY INVISIBLE (-6450 2600);
FORCEPROP 1 LAST OFFPAGE TRUE
J 0
(-6125 2475);
DISPLAY 1.170213 (-6125 2475);
PAINT GREEN (-6125 2475);
DISPLAY INVISIBLE (-6125 2475);
FORCEPROP 1 LAST COMMENT_BODY TRUE
J 0
(-6325 2500);
DISPLAY 1.170213 (-6325 2500);
PAINT GREEN (-6325 2500);
DISPLAY INVISIBLE (-6325 2500);
FORCEPROP 2 LAST PATH I1
J 0
(-6400 2675);
DISPLAY 1.021277 (-6400 2675);
PAINT ORANGE (-6400 2675);
DISPLAY INVISIBLE (-6400 2675);
FORCEADD TAP..1
R 2
(-5250 1900);
FORCEPROP 3 LASTPIN (-5200 1900) SIG_NAME UPI_CPU1_CPU0_P0P0_DN<13>
J 0
(-5190 1910);
DISPLAY 0.659574 (-5190 1910);
PAINT MONO (-5190 1910);
DISPLAY INVISIBLE (-5190 1910);
FORCEPROP 1 LASTPIN (-5200 1900) BN 13
J 2
(-5188 1908);
DISPLAY 0.617021 (-5188 1908);
PAINT PINK (-5188 1908);
FORCEPROP 2 LAST CDS_LIB mstr_standard
J 0
(-5250 1900);
PAINT MONO (-5250 1900);
DISPLAY INVISIBLE (-5250 1900);
FORCEPROP 1 LAST BODY_TYPE PLUMBING
J 2
(-5250 1950);
DISPLAY 1.446809 (-5250 1950);
PAINT GREEN (-5250 1950);
DISPLAY INVISIBLE (-5250 1950);
FORCEPROP 1 LAST HDL_TAP TRUE
J 2
(-5575 1775);
DISPLAY 1.446809 (-5575 1775);
PAINT GREEN (-5575 1775);
DISPLAY INVISIBLE (-5575 1775);
FORCEPROP 1 LAST PATH I10
J 2
(-5248 1900);
DISPLAY 0.872340 (-5248 1900);
PAINT GREEN (-5248 1900);
DISPLAY INVISIBLE (-5248 1900);
FORCEADD TAP..1
R 2
(-5250 2000);
FORCEPROP 3 LASTPIN (-5200 2000) SIG_NAME UPI_CPU1_CPU0_P0P0_DN<11>
J 0
(-5190 2010);
DISPLAY 0.659574 (-5190 2010);
PAINT MONO (-5190 2010);
DISPLAY INVISIBLE (-5190 2010);
FORCEPROP 1 LASTPIN (-5200 2000) BN 11
J 2
(-5188 2008);
DISPLAY 0.617021 (-5188 2008);
PAINT PINK (-5188 2008);
FORCEPROP 2 LAST CDS_LIB mstr_standard
J 0
(-5250 2000);
PAINT MONO (-5250 2000);
DISPLAY INVISIBLE (-5250 2000);
FORCEPROP 1 LAST BODY_TYPE PLUMBING
J 2
(-5250 2050);
DISPLAY 1.446809 (-5250 2050);
PAINT GREEN (-5250 2050);
DISPLAY INVISIBLE (-5250 2050);
FORCEPROP 1 LAST HDL_TAP TRUE
J 2
(-5575 1875);
DISPLAY 1.446809 (-5575 1875);
PAINT GREEN (-5575 1875);
DISPLAY INVISIBLE (-5575 1875);
FORCEPROP 1 LAST PATH I11
J 2
(-5248 2000);
DISPLAY 0.872340 (-5248 2000);
PAINT GREEN (-5248 2000);
DISPLAY INVISIBLE (-5248 2000);
FORCEADD TAP..1
R 2
(-5250 2100);
FORCEPROP 3 LASTPIN (-5200 2100) SIG_NAME UPI_CPU1_CPU0_P0P0_DN<9>
J 0
(-5190 2110);
DISPLAY 0.659574 (-5190 2110);
PAINT MONO (-5190 2110);
DISPLAY INVISIBLE (-5190 2110);
FORCEPROP 1 LASTPIN (-5200 2100) BN 9
J 2
(-5188 2108);
DISPLAY 0.617021 (-5188 2108);
PAINT PINK (-5188 2108);
FORCEPROP 2 LAST CDS_LIB mstr_standard
J 0
(-5250 2100);
PAINT MONO (-5250 2100);
DISPLAY INVISIBLE (-5250 2100);
FORCEPROP 1 LAST BODY_TYPE PLUMBING
J 2
(-5250 2150);
DISPLAY 1.446809 (-5250 2150);
PAINT GREEN (-5250 2150);
DISPLAY INVISIBLE (-5250 2150);
FORCEPROP 1 LAST HDL_TAP TRUE
J 2
(-5575 1975);
DISPLAY 1.446809 (-5575 1975);
PAINT GREEN (-5575 1975);
DISPLAY INVISIBLE (-5575 1975);
FORCEPROP 1 LAST PATH I13
J 2
(-5248 2100);
DISPLAY 0.872340 (-5248 2100);
PAINT GREEN (-5248 2100);
DISPLAY INVISIBLE (-5248 2100);
FORCEADD TAP..1
R 2
(-5250 2050);
FORCEPROP 3 LASTPIN (-5200 2050) SIG_NAME UPI_CPU1_CPU0_P0P0_DN<10>
J 0
(-5190 2060);
DISPLAY 0.659574 (-5190 2060);
PAINT MONO (-5190 2060);
DISPLAY INVISIBLE (-5190 2060);
FORCEPROP 1 LASTPIN (-5200 2050) BN 10
J 2
(-5188 2058);
DISPLAY 0.617021 (-5188 2058);
PAINT PINK (-5188 2058);
FORCEPROP 2 LAST CDS_LIB mstr_standard
J 0
(-5250 2050);
PAINT MONO (-5250 2050);
DISPLAY INVISIBLE (-5250 2050);
FORCEPROP 1 LAST BODY_TYPE PLUMBING
J 2
(-5250 2100);
DISPLAY 1.446809 (-5250 2100);
PAINT GREEN (-5250 2100);
DISPLAY INVISIBLE (-5250 2100);
FORCEPROP 1 LAST HDL_TAP TRUE
J 2
(-5575 1925);
DISPLAY 1.446809 (-5575 1925);
PAINT GREEN (-5575 1925);
DISPLAY INVISIBLE (-5575 1925);
FORCEPROP 1 LAST PATH I14
J 2
(-5248 2050);
DISPLAY 0.872340 (-5248 2050);
PAINT GREEN (-5248 2050);
DISPLAY INVISIBLE (-5248 2050);
FORCEADD TAP..1
R 2
(-5250 2250);
FORCEPROP 3 LASTPIN (-5200 2250) SIG_NAME UPI_CPU1_CPU0_P0P0_DN<6>
J 0
(-5190 2260);
DISPLAY 0.659574 (-5190 2260);
PAINT MONO (-5190 2260);
DISPLAY INVISIBLE (-5190 2260);
FORCEPROP 1 LASTPIN (-5200 2250) BN 6
J 2
(-5188 2258);
DISPLAY 0.617021 (-5188 2258);
PAINT PINK (-5188 2258);
FORCEPROP 2 LAST CDS_LIB mstr_standard
J 0
(-5250 2250);
PAINT MONO (-5250 2250);
DISPLAY INVISIBLE (-5250 2250);
FORCEPROP 1 LAST BODY_TYPE PLUMBING
J 2
(-5250 2300);
DISPLAY 1.446809 (-5250 2300);
PAINT GREEN (-5250 2300);
DISPLAY INVISIBLE (-5250 2300);
FORCEPROP 1 LAST HDL_TAP TRUE
J 2
(-5575 2125);
DISPLAY 1.446809 (-5575 2125);
PAINT GREEN (-5575 2125);
DISPLAY INVISIBLE (-5575 2125);
FORCEPROP 1 LAST PATH I15
J 2
(-5248 2250);
DISPLAY 0.872340 (-5248 2250);
PAINT GREEN (-5248 2250);
DISPLAY INVISIBLE (-5248 2250);
FORCEADD TAP..1
R 2
(-5250 2200);
FORCEPROP 3 LASTPIN (-5200 2200) SIG_NAME UPI_CPU1_CPU0_P0P0_DN<7>
J 0
(-5190 2210);
DISPLAY 0.659574 (-5190 2210);
PAINT MONO (-5190 2210);
DISPLAY INVISIBLE (-5190 2210);
FORCEPROP 1 LASTPIN (-5200 2200) BN 7
J 2
(-5188 2208);
DISPLAY 0.617021 (-5188 2208);
PAINT PINK (-5188 2208);
FORCEPROP 2 LAST CDS_LIB mstr_standard
J 0
(-5250 2200);
PAINT MONO (-5250 2200);
DISPLAY INVISIBLE (-5250 2200);
FORCEPROP 1 LAST BODY_TYPE PLUMBING
J 2
(-5250 2250);
DISPLAY 1.446809 (-5250 2250);
PAINT GREEN (-5250 2250);
DISPLAY INVISIBLE (-5250 2250);
FORCEPROP 1 LAST HDL_TAP TRUE
J 2
(-5575 2075);
DISPLAY 1.446809 (-5575 2075);
PAINT GREEN (-5575 2075);
DISPLAY INVISIBLE (-5575 2075);
FORCEPROP 1 LAST PATH I16
J 2
(-5248 2200);
DISPLAY 0.872340 (-5248 2200);
PAINT GREEN (-5248 2200);
DISPLAY INVISIBLE (-5248 2200);
FORCEADD TAP..1
R 2
(-5250 2150);
FORCEPROP 3 LASTPIN (-5200 2150) SIG_NAME UPI_CPU1_CPU0_P0P0_DN<8>
J 0
(-5190 2160);
DISPLAY 0.659574 (-5190 2160);
PAINT MONO (-5190 2160);
DISPLAY INVISIBLE (-5190 2160);
FORCEPROP 1 LASTPIN (-5200 2150) BN 8
J 2
(-5188 2158);
DISPLAY 0.617021 (-5188 2158);
PAINT PINK (-5188 2158);
FORCEPROP 2 LAST CDS_LIB mstr_standard
J 0
(-5250 2150);
PAINT MONO (-5250 2150);
DISPLAY INVISIBLE (-5250 2150);
FORCEPROP 1 LAST BODY_TYPE PLUMBING
J 2
(-5250 2200);
DISPLAY 1.446809 (-5250 2200);
PAINT GREEN (-5250 2200);
DISPLAY INVISIBLE (-5250 2200);
FORCEPROP 1 LAST HDL_TAP TRUE
J 2
(-5575 2025);
DISPLAY 1.446809 (-5575 2025);
PAINT GREEN (-5575 2025);
DISPLAY INVISIBLE (-5575 2025);
FORCEPROP 1 LAST PATH I17
J 2
(-5248 2150);
DISPLAY 0.872340 (-5248 2150);
PAINT GREEN (-5248 2150);
DISPLAY INVISIBLE (-5248 2150);
FORCEADD TAP..1
R 2
(-5250 2350);
FORCEPROP 3 LASTPIN (-5200 2350) SIG_NAME UPI_CPU1_CPU0_P0P0_DN<4>
J 0
(-5190 2360);
DISPLAY 0.659574 (-5190 2360);
PAINT MONO (-5190 2360);
DISPLAY INVISIBLE (-5190 2360);
FORCEPROP 1 LASTPIN (-5200 2350) BN 4
J 2
(-5188 2358);
DISPLAY 0.617021 (-5188 2358);
PAINT PINK (-5188 2358);
FORCEPROP 2 LAST CDS_LIB mstr_standard
J 0
(-5250 2350);
PAINT MONO (-5250 2350);
DISPLAY INVISIBLE (-5250 2350);
FORCEPROP 1 LAST BODY_TYPE PLUMBING
J 2
(-5250 2400);
DISPLAY 1.446809 (-5250 2400);
PAINT GREEN (-5250 2400);
DISPLAY INVISIBLE (-5250 2400);
FORCEPROP 1 LAST HDL_TAP TRUE
J 2
(-5575 2225);
DISPLAY 1.446809 (-5575 2225);
PAINT GREEN (-5575 2225);
DISPLAY INVISIBLE (-5575 2225);
FORCEPROP 1 LAST PATH I18
J 2
(-5248 2350);
DISPLAY 0.872340 (-5248 2350);
PAINT GREEN (-5248 2350);
DISPLAY INVISIBLE (-5248 2350);
FORCEADD TAP..1
R 2
(-5250 2300);
FORCEPROP 3 LASTPIN (-5200 2300) SIG_NAME UPI_CPU1_CPU0_P0P0_DN<5>
J 0
(-5190 2310);
DISPLAY 0.659574 (-5190 2310);
PAINT MONO (-5190 2310);
DISPLAY INVISIBLE (-5190 2310);
FORCEPROP 1 LASTPIN (-5200 2300) BN 5
J 2
(-5188 2308);
DISPLAY 0.617021 (-5188 2308);
PAINT PINK (-5188 2308);
FORCEPROP 2 LAST CDS_LIB mstr_standard
J 0
(-5250 2300);
PAINT MONO (-5250 2300);
DISPLAY INVISIBLE (-5250 2300);
FORCEPROP 1 LAST BODY_TYPE PLUMBING
J 2
(-5250 2350);
DISPLAY 1.446809 (-5250 2350);
PAINT GREEN (-5250 2350);
DISPLAY INVISIBLE (-5250 2350);
FORCEPROP 1 LAST HDL_TAP TRUE
J 2
(-5575 2175);
DISPLAY 1.446809 (-5575 2175);
PAINT GREEN (-5575 2175);
DISPLAY INVISIBLE (-5575 2175);
FORCEPROP 1 LAST PATH I19
J 2
(-5248 2300);
DISPLAY 0.872340 (-5248 2300);
PAINT GREEN (-5248 2300);
DISPLAY INVISIBLE (-5248 2300);
FORCEADD OFFPAGE..1
(-6450 3650);
FORCEPROP 2 LAST $XR0 67 
J 0
(-6701 3650);
DISPLAY 0.638298 (-6701 3650);
PAINT MONO (-6701 3650);
FORCEPROP 2 LAST CDS_LIB mstr_standard
J 0
(-6450 3650);
PAINT MONO (-6450 3650);
DISPLAY INVISIBLE (-6450 3650);
FORCEPROP 1 LAST OFFPAGE TRUE
J 0
(-6125 3525);
DISPLAY 1.170213 (-6125 3525);
PAINT GREEN (-6125 3525);
DISPLAY INVISIBLE (-6125 3525);
FORCEPROP 1 LAST COMMENT_BODY TRUE
J 0
(-6325 3550);
DISPLAY 1.170213 (-6325 3550);
PAINT GREEN (-6325 3550);
DISPLAY INVISIBLE (-6325 3550);
FORCEPROP 2 LAST PATH I2
J 0
(-6400 3725);
DISPLAY 1.021277 (-6400 3725);
PAINT ORANGE (-6400 3725);
DISPLAY INVISIBLE (-6400 3725);
FORCEADD TAP..1
R 2
(-5250 2500);
FORCEPROP 3 LASTPIN (-5200 2500) SIG_NAME UPI_CPU1_CPU0_P0P0_DN<1>
J 0
(-5190 2510);
DISPLAY 0.659574 (-5190 2510);
PAINT MONO (-5190 2510);
DISPLAY INVISIBLE (-5190 2510);
FORCEPROP 1 LASTPIN (-5200 2500) BN 1
J 2
(-5188 2508);
DISPLAY 0.617021 (-5188 2508);
PAINT PINK (-5188 2508);
FORCEPROP 2 LAST CDS_LIB mstr_standard
J 0
(-5250 2500);
PAINT MONO (-5250 2500);
DISPLAY INVISIBLE (-5250 2500);
FORCEPROP 1 LAST BODY_TYPE PLUMBING
J 2
(-5250 2550);
DISPLAY 1.446809 (-5250 2550);
PAINT GREEN (-5250 2550);
DISPLAY INVISIBLE (-5250 2550);
FORCEPROP 1 LAST HDL_TAP TRUE
J 2
(-5575 2375);
DISPLAY 1.446809 (-5575 2375);
PAINT GREEN (-5575 2375);
DISPLAY INVISIBLE (-5575 2375);
FORCEPROP 1 LAST PATH I20
J 2
(-5248 2500);
DISPLAY 0.872340 (-5248 2500);
PAINT GREEN (-5248 2500);
DISPLAY INVISIBLE (-5248 2500);
FORCEADD TAP..1
R 2
(-5250 2450);
FORCEPROP 3 LASTPIN (-5200 2450) SIG_NAME UPI_CPU1_CPU0_P0P0_DN<2>
J 0
(-5190 2460);
DISPLAY 0.659574 (-5190 2460);
PAINT MONO (-5190 2460);
DISPLAY INVISIBLE (-5190 2460);
FORCEPROP 1 LASTPIN (-5200 2450) BN 2
J 2
(-5188 2458);
DISPLAY 0.617021 (-5188 2458);
PAINT PINK (-5188 2458);
FORCEPROP 2 LAST CDS_LIB mstr_standard
J 0
(-5250 2450);
PAINT MONO (-5250 2450);
DISPLAY INVISIBLE (-5250 2450);
FORCEPROP 1 LAST BODY_TYPE PLUMBING
J 2
(-5250 2500);
DISPLAY 1.446809 (-5250 2500);
PAINT GREEN (-5250 2500);
DISPLAY INVISIBLE (-5250 2500);
FORCEPROP 1 LAST HDL_TAP TRUE
J 2
(-5575 2325);
DISPLAY 1.446809 (-5575 2325);
PAINT GREEN (-5575 2325);
DISPLAY INVISIBLE (-5575 2325);
FORCEPROP 1 LAST PATH I21
J 2
(-5248 2450);
DISPLAY 0.872340 (-5248 2450);
PAINT GREEN (-5248 2450);
DISPLAY INVISIBLE (-5248 2450);
FORCEADD TAP..1
R 2
(-5250 2400);
FORCEPROP 3 LASTPIN (-5200 2400) SIG_NAME UPI_CPU1_CPU0_P0P0_DN<3>
J 0
(-5190 2410);
DISPLAY 0.659574 (-5190 2410);
PAINT MONO (-5190 2410);
DISPLAY INVISIBLE (-5190 2410);
FORCEPROP 1 LASTPIN (-5200 2400) BN 3
J 2
(-5188 2408);
DISPLAY 0.617021 (-5188 2408);
PAINT PINK (-5188 2408);
FORCEPROP 2 LAST CDS_LIB mstr_standard
J 0
(-5250 2400);
PAINT MONO (-5250 2400);
DISPLAY INVISIBLE (-5250 2400);
FORCEPROP 1 LAST BODY_TYPE PLUMBING
J 2
(-5250 2450);
DISPLAY 1.446809 (-5250 2450);
PAINT GREEN (-5250 2450);
DISPLAY INVISIBLE (-5250 2450);
FORCEPROP 1 LAST HDL_TAP TRUE
J 2
(-5575 2275);
DISPLAY 1.446809 (-5575 2275);
PAINT GREEN (-5575 2275);
DISPLAY INVISIBLE (-5575 2275);
FORCEPROP 1 LAST PATH I22
J 2
(-5248 2400);
DISPLAY 0.872340 (-5248 2400);
PAINT GREEN (-5248 2400);
DISPLAY INVISIBLE (-5248 2400);
FORCEADD TAP..1
R 2
(-5250 2750);
FORCEPROP 3 LASTPIN (-5200 2750) SIG_NAME UPI_CPU1_CPU0_P0P0_DP<17>
J 0
(-5190 2760);
DISPLAY 0.659574 (-5190 2760);
PAINT MONO (-5190 2760);
DISPLAY INVISIBLE (-5190 2760);
FORCEPROP 1 LASTPIN (-5200 2750) BN 17
J 2
(-5188 2758);
DISPLAY 0.617021 (-5188 2758);
PAINT PINK (-5188 2758);
FORCEPROP 2 LAST CDS_LIB mstr_standard
J 0
(-5250 2750);
PAINT MONO (-5250 2750);
DISPLAY INVISIBLE (-5250 2750);
FORCEPROP 1 LAST BODY_TYPE PLUMBING
J 2
(-5250 2800);
DISPLAY 1.446809 (-5250 2800);
PAINT GREEN (-5250 2800);
DISPLAY INVISIBLE (-5250 2800);
FORCEPROP 1 LAST HDL_TAP TRUE
J 2
(-5575 2625);
DISPLAY 1.446809 (-5575 2625);
PAINT GREEN (-5575 2625);
DISPLAY INVISIBLE (-5575 2625);
FORCEPROP 1 LAST PATH I23
J 2
(-5248 2750);
DISPLAY 0.872340 (-5248 2750);
PAINT GREEN (-5248 2750);
DISPLAY INVISIBLE (-5248 2750);
FORCEADD TAP..1
R 2
(-5250 2650);
FORCEPROP 3 LASTPIN (-5200 2650) SIG_NAME UPI_CPU1_CPU0_P0P0_DP<19>
J 0
(-5190 2660);
DISPLAY 0.659574 (-5190 2660);
PAINT MONO (-5190 2660);
DISPLAY INVISIBLE (-5190 2660);
FORCEPROP 1 LASTPIN (-5200 2650) BN 19
J 2
(-5188 2658);
DISPLAY 0.617021 (-5188 2658);
PAINT PINK (-5188 2658);
FORCEPROP 2 LAST CDS_LIB mstr_standard
J 0
(-5250 2650);
PAINT MONO (-5250 2650);
DISPLAY INVISIBLE (-5250 2650);
FORCEPROP 1 LAST BODY_TYPE PLUMBING
J 2
(-5250 2700);
DISPLAY 1.446809 (-5250 2700);
PAINT GREEN (-5250 2700);
DISPLAY INVISIBLE (-5250 2700);
FORCEPROP 1 LAST HDL_TAP TRUE
J 2
(-5575 2525);
DISPLAY 1.446809 (-5575 2525);
PAINT GREEN (-5575 2525);
DISPLAY INVISIBLE (-5575 2525);
FORCEPROP 1 LAST PATH I24
J 2
(-5248 2650);
DISPLAY 0.872340 (-5248 2650);
PAINT GREEN (-5248 2650);
DISPLAY INVISIBLE (-5248 2650);
FORCEADD TAP..1
R 2
(-5250 2700);
FORCEPROP 3 LASTPIN (-5200 2700) SIG_NAME UPI_CPU1_CPU0_P0P0_DP<18>
J 0
(-5190 2710);
DISPLAY 0.659574 (-5190 2710);
PAINT MONO (-5190 2710);
DISPLAY INVISIBLE (-5190 2710);
FORCEPROP 1 LASTPIN (-5200 2700) BN 18
J 2
(-5188 2708);
DISPLAY 0.617021 (-5188 2708);
PAINT PINK (-5188 2708);
FORCEPROP 2 LAST CDS_LIB mstr_standard
J 0
(-5250 2700);
PAINT MONO (-5250 2700);
DISPLAY INVISIBLE (-5250 2700);
FORCEPROP 1 LAST BODY_TYPE PLUMBING
J 2
(-5250 2750);
DISPLAY 1.446809 (-5250 2750);
PAINT GREEN (-5250 2750);
DISPLAY INVISIBLE (-5250 2750);
FORCEPROP 1 LAST HDL_TAP TRUE
J 2
(-5575 2575);
DISPLAY 1.446809 (-5575 2575);
PAINT GREEN (-5575 2575);
DISPLAY INVISIBLE (-5575 2575);
FORCEPROP 1 LAST PATH I25
J 2
(-5248 2700);
DISPLAY 0.872340 (-5248 2700);
PAINT GREEN (-5248 2700);
DISPLAY INVISIBLE (-5248 2700);
FORCEADD TAP..1
R 2
(-5250 2550);
FORCEPROP 3 LASTPIN (-5200 2550) SIG_NAME UPI_CPU1_CPU0_P0P0_DN<0>
J 0
(-5190 2560);
DISPLAY 0.659574 (-5190 2560);
PAINT MONO (-5190 2560);
DISPLAY INVISIBLE (-5190 2560);
FORCEPROP 1 LASTPIN (-5200 2550) BN 0
J 2
(-5188 2558);
DISPLAY 0.617021 (-5188 2558);
PAINT PINK (-5188 2558);
FORCEPROP 2 LAST CDS_LIB mstr_standard
J 0
(-5250 2550);
PAINT MONO (-5250 2550);
DISPLAY INVISIBLE (-5250 2550);
FORCEPROP 1 LAST BODY_TYPE PLUMBING
J 2
(-5250 2600);
DISPLAY 1.446809 (-5250 2600);
PAINT GREEN (-5250 2600);
DISPLAY INVISIBLE (-5250 2600);
FORCEPROP 1 LAST HDL_TAP TRUE
J 2
(-5575 2425);
DISPLAY 1.446809 (-5575 2425);
PAINT GREEN (-5575 2425);
DISPLAY INVISIBLE (-5575 2425);
FORCEPROP 1 LAST PATH I26
J 2
(-5248 2550);
DISPLAY 0.872340 (-5248 2550);
PAINT GREEN (-5248 2550);
DISPLAY INVISIBLE (-5248 2550);
FORCEADD TAP..1
R 2
(-5250 2850);
FORCEPROP 3 LASTPIN (-5200 2850) SIG_NAME UPI_CPU1_CPU0_P0P0_DP<15>
J 0
(-5190 2860);
DISPLAY 0.659574 (-5190 2860);
PAINT MONO (-5190 2860);
DISPLAY INVISIBLE (-5190 2860);
FORCEPROP 1 LASTPIN (-5200 2850) BN 15
J 2
(-5188 2858);
DISPLAY 0.617021 (-5188 2858);
PAINT PINK (-5188 2858);
FORCEPROP 2 LAST CDS_LIB mstr_standard
J 0
(-5250 2850);
PAINT MONO (-5250 2850);
DISPLAY INVISIBLE (-5250 2850);
FORCEPROP 1 LAST BODY_TYPE PLUMBING
J 2
(-5250 2900);
DISPLAY 1.446809 (-5250 2900);
PAINT GREEN (-5250 2900);
DISPLAY INVISIBLE (-5250 2900);
FORCEPROP 1 LAST HDL_TAP TRUE
J 2
(-5575 2725);
DISPLAY 1.446809 (-5575 2725);
PAINT GREEN (-5575 2725);
DISPLAY INVISIBLE (-5575 2725);
FORCEPROP 1 LAST PATH I27
J 2
(-5248 2850);
DISPLAY 0.872340 (-5248 2850);
PAINT GREEN (-5248 2850);
DISPLAY INVISIBLE (-5248 2850);
FORCEADD TAP..1
R 2
(-5250 2800);
FORCEPROP 3 LASTPIN (-5200 2800) SIG_NAME UPI_CPU1_CPU0_P0P0_DP<16>
J 0
(-5190 2810);
DISPLAY 0.659574 (-5190 2810);
PAINT MONO (-5190 2810);
DISPLAY INVISIBLE (-5190 2810);
FORCEPROP 1 LASTPIN (-5200 2800) BN 16
J 2
(-5188 2808);
DISPLAY 0.617021 (-5188 2808);
PAINT PINK (-5188 2808);
FORCEPROP 2 LAST CDS_LIB mstr_standard
J 0
(-5250 2800);
PAINT MONO (-5250 2800);
DISPLAY INVISIBLE (-5250 2800);
FORCEPROP 1 LAST BODY_TYPE PLUMBING
J 2
(-5250 2850);
DISPLAY 1.446809 (-5250 2850);
PAINT GREEN (-5250 2850);
DISPLAY INVISIBLE (-5250 2850);
FORCEPROP 1 LAST HDL_TAP TRUE
J 2
(-5575 2675);
DISPLAY 1.446809 (-5575 2675);
PAINT GREEN (-5575 2675);
DISPLAY INVISIBLE (-5575 2675);
FORCEPROP 1 LAST PATH I28
J 2
(-5248 2800);
DISPLAY 0.872340 (-5248 2800);
PAINT GREEN (-5248 2800);
DISPLAY INVISIBLE (-5248 2800);
FORCEADD TAP..1
R 2
(-5250 2950);
FORCEPROP 3 LASTPIN (-5200 2950) SIG_NAME UPI_CPU1_CPU0_P0P0_DP<13>
J 0
(-5190 2960);
DISPLAY 0.659574 (-5190 2960);
PAINT MONO (-5190 2960);
DISPLAY INVISIBLE (-5190 2960);
FORCEPROP 1 LASTPIN (-5200 2950) BN 13
J 2
(-5188 2958);
DISPLAY 0.617021 (-5188 2958);
PAINT PINK (-5188 2958);
FORCEPROP 2 LAST CDS_LIB mstr_standard
J 0
(-5250 2950);
PAINT MONO (-5250 2950);
DISPLAY INVISIBLE (-5250 2950);
FORCEPROP 1 LAST BODY_TYPE PLUMBING
J 2
(-5250 3000);
DISPLAY 1.446809 (-5250 3000);
PAINT GREEN (-5250 3000);
DISPLAY INVISIBLE (-5250 3000);
FORCEPROP 1 LAST HDL_TAP TRUE
J 2
(-5575 2825);
DISPLAY 1.446809 (-5575 2825);
PAINT GREEN (-5575 2825);
DISPLAY INVISIBLE (-5575 2825);
FORCEPROP 1 LAST PATH I29
J 2
(-5248 2950);
DISPLAY 0.872340 (-5248 2950);
PAINT GREEN (-5248 2950);
DISPLAY INVISIBLE (-5248 2950);
FORCEADD TAP..1
R 2
(-5250 1600);
FORCEPROP 3 LASTPIN (-5200 1600) SIG_NAME UPI_CPU1_CPU0_P0P0_DN<19>
J 0
(-5190 1610);
DISPLAY 0.659574 (-5190 1610);
PAINT MONO (-5190 1610);
DISPLAY INVISIBLE (-5190 1610);
FORCEPROP 1 LASTPIN (-5200 1600) BN 19
J 2
(-5188 1608);
DISPLAY 0.617021 (-5188 1608);
PAINT PINK (-5188 1608);
FORCEPROP 2 LAST CDS_LIB mstr_standard
J 0
(-5250 1600);
PAINT MONO (-5250 1600);
DISPLAY INVISIBLE (-5250 1600);
FORCEPROP 1 LAST BODY_TYPE PLUMBING
J 2
(-5250 1650);
DISPLAY 1.446809 (-5250 1650);
PAINT GREEN (-5250 1650);
DISPLAY INVISIBLE (-5250 1650);
FORCEPROP 1 LAST HDL_TAP TRUE
J 2
(-5575 1475);
DISPLAY 1.446809 (-5575 1475);
PAINT GREEN (-5575 1475);
DISPLAY INVISIBLE (-5575 1475);
FORCEPROP 1 LAST PATH I3
J 2
(-5248 1600);
DISPLAY 0.872340 (-5248 1600);
PAINT GREEN (-5248 1600);
DISPLAY INVISIBLE (-5248 1600);
FORCEADD TAP..1
R 2
(-5250 3000);
FORCEPROP 3 LASTPIN (-5200 3000) SIG_NAME UPI_CPU1_CPU0_P0P0_DP<12>
J 0
(-5190 3010);
DISPLAY 0.659574 (-5190 3010);
PAINT MONO (-5190 3010);
DISPLAY INVISIBLE (-5190 3010);
FORCEPROP 1 LASTPIN (-5200 3000) BN 12
J 2
(-5188 3008);
DISPLAY 0.617021 (-5188 3008);
PAINT PINK (-5188 3008);
FORCEPROP 2 LAST CDS_LIB mstr_standard
J 0
(-5250 3000);
PAINT MONO (-5250 3000);
DISPLAY INVISIBLE (-5250 3000);
FORCEPROP 1 LAST BODY_TYPE PLUMBING
J 2
(-5250 3050);
DISPLAY 1.446809 (-5250 3050);
PAINT GREEN (-5250 3050);
DISPLAY INVISIBLE (-5250 3050);
FORCEPROP 1 LAST HDL_TAP TRUE
J 2
(-5575 2875);
DISPLAY 1.446809 (-5575 2875);
PAINT GREEN (-5575 2875);
DISPLAY INVISIBLE (-5575 2875);
FORCEPROP 1 LAST PATH I30
J 2
(-5248 3000);
DISPLAY 0.872340 (-5248 3000);
PAINT GREEN (-5248 3000);
DISPLAY INVISIBLE (-5248 3000);
FORCEADD TAP..1
R 2
(-5250 2900);
FORCEPROP 3 LASTPIN (-5200 2900) SIG_NAME UPI_CPU1_CPU0_P0P0_DP<14>
J 0
(-5190 2910);
DISPLAY 0.659574 (-5190 2910);
PAINT MONO (-5190 2910);
DISPLAY INVISIBLE (-5190 2910);
FORCEPROP 1 LASTPIN (-5200 2900) BN 14
J 2
(-5188 2908);
DISPLAY 0.617021 (-5188 2908);
PAINT PINK (-5188 2908);
FORCEPROP 2 LAST CDS_LIB mstr_standard
J 0
(-5250 2900);
PAINT MONO (-5250 2900);
DISPLAY INVISIBLE (-5250 2900);
FORCEPROP 1 LAST BODY_TYPE PLUMBING
J 2
(-5250 2950);
DISPLAY 1.446809 (-5250 2950);
PAINT GREEN (-5250 2950);
DISPLAY INVISIBLE (-5250 2950);
FORCEPROP 1 LAST HDL_TAP TRUE
J 2
(-5575 2775);
DISPLAY 1.446809 (-5575 2775);
PAINT GREEN (-5575 2775);
DISPLAY INVISIBLE (-5575 2775);
FORCEPROP 1 LAST PATH I31
J 2
(-5248 2900);
DISPLAY 0.872340 (-5248 2900);
PAINT GREEN (-5248 2900);
DISPLAY INVISIBLE (-5248 2900);
FORCEADD TAP..1
R 2
(-5250 3050);
FORCEPROP 3 LASTPIN (-5200 3050) SIG_NAME UPI_CPU1_CPU0_P0P0_DP<11>
J 0
(-5190 3060);
DISPLAY 0.659574 (-5190 3060);
PAINT MONO (-5190 3060);
DISPLAY INVISIBLE (-5190 3060);
FORCEPROP 1 LASTPIN (-5200 3050) BN 11
J 2
(-5188 3058);
DISPLAY 0.617021 (-5188 3058);
PAINT PINK (-5188 3058);
FORCEPROP 2 LAST CDS_LIB mstr_standard
J 0
(-5250 3050);
PAINT MONO (-5250 3050);
DISPLAY INVISIBLE (-5250 3050);
FORCEPROP 1 LAST BODY_TYPE PLUMBING
J 2
(-5250 3100);
DISPLAY 1.446809 (-5250 3100);
PAINT GREEN (-5250 3100);
DISPLAY INVISIBLE (-5250 3100);
FORCEPROP 1 LAST HDL_TAP TRUE
J 2
(-5575 2925);
DISPLAY 1.446809 (-5575 2925);
PAINT GREEN (-5575 2925);
DISPLAY INVISIBLE (-5575 2925);
FORCEPROP 1 LAST PATH I32
J 2
(-5248 3050);
DISPLAY 0.872340 (-5248 3050);
PAINT GREEN (-5248 3050);
DISPLAY INVISIBLE (-5248 3050);
FORCEADD TAP..1
R 2
(-5250 3100);
FORCEPROP 3 LASTPIN (-5200 3100) SIG_NAME UPI_CPU1_CPU0_P0P0_DP<10>
J 0
(-5190 3110);
DISPLAY 0.659574 (-5190 3110);
PAINT MONO (-5190 3110);
DISPLAY INVISIBLE (-5190 3110);
FORCEPROP 1 LASTPIN (-5200 3100) BN 10
J 2
(-5188 3108);
DISPLAY 0.617021 (-5188 3108);
PAINT PINK (-5188 3108);
FORCEPROP 2 LAST CDS_LIB mstr_standard
J 0
(-5250 3100);
PAINT MONO (-5250 3100);
DISPLAY INVISIBLE (-5250 3100);
FORCEPROP 1 LAST BODY_TYPE PLUMBING
J 2
(-5250 3150);
DISPLAY 1.446809 (-5250 3150);
PAINT GREEN (-5250 3150);
DISPLAY INVISIBLE (-5250 3150);
FORCEPROP 1 LAST HDL_TAP TRUE
J 2
(-5575 2975);
DISPLAY 1.446809 (-5575 2975);
PAINT GREEN (-5575 2975);
DISPLAY INVISIBLE (-5575 2975);
FORCEPROP 1 LAST PATH I33
J 2
(-5248 3100);
DISPLAY 0.872340 (-5248 3100);
PAINT GREEN (-5248 3100);
DISPLAY INVISIBLE (-5248 3100);
FORCEADD TAP..1
R 2
(-5250 3150);
FORCEPROP 3 LASTPIN (-5200 3150) SIG_NAME UPI_CPU1_CPU0_P0P0_DP<9>
J 0
(-5190 3160);
DISPLAY 0.659574 (-5190 3160);
PAINT MONO (-5190 3160);
DISPLAY INVISIBLE (-5190 3160);
FORCEPROP 1 LASTPIN (-5200 3150) BN 9
J 2
(-5188 3158);
DISPLAY 0.617021 (-5188 3158);
PAINT PINK (-5188 3158);
FORCEPROP 2 LAST CDS_LIB mstr_standard
J 0
(-5250 3150);
PAINT MONO (-5250 3150);
DISPLAY INVISIBLE (-5250 3150);
FORCEPROP 1 LAST BODY_TYPE PLUMBING
J 2
(-5250 3200);
DISPLAY 1.446809 (-5250 3200);
PAINT GREEN (-5250 3200);
DISPLAY INVISIBLE (-5250 3200);
FORCEPROP 1 LAST HDL_TAP TRUE
J 2
(-5575 3025);
DISPLAY 1.446809 (-5575 3025);
PAINT GREEN (-5575 3025);
DISPLAY INVISIBLE (-5575 3025);
FORCEPROP 1 LAST PATH I34
J 2
(-5248 3150);
DISPLAY 0.872340 (-5248 3150);
PAINT GREEN (-5248 3150);
DISPLAY INVISIBLE (-5248 3150);
FORCEADD TAP..1
R 2
(-5250 3250);
FORCEPROP 3 LASTPIN (-5200 3250) SIG_NAME UPI_CPU1_CPU0_P0P0_DP<7>
J 0
(-5190 3260);
DISPLAY 0.659574 (-5190 3260);
PAINT MONO (-5190 3260);
DISPLAY INVISIBLE (-5190 3260);
FORCEPROP 1 LASTPIN (-5200 3250) BN 7
J 2
(-5188 3258);
DISPLAY 0.617021 (-5188 3258);
PAINT PINK (-5188 3258);
FORCEPROP 2 LAST CDS_LIB mstr_standard
J 0
(-5250 3250);
PAINT MONO (-5250 3250);
DISPLAY INVISIBLE (-5250 3250);
FORCEPROP 1 LAST BODY_TYPE PLUMBING
J 2
(-5250 3300);
DISPLAY 1.446809 (-5250 3300);
PAINT GREEN (-5250 3300);
DISPLAY INVISIBLE (-5250 3300);
FORCEPROP 1 LAST HDL_TAP TRUE
J 2
(-5575 3125);
DISPLAY 1.446809 (-5575 3125);
PAINT GREEN (-5575 3125);
DISPLAY INVISIBLE (-5575 3125);
FORCEPROP 1 LAST PATH I35
J 2
(-5248 3250);
DISPLAY 0.872340 (-5248 3250);
PAINT GREEN (-5248 3250);
DISPLAY INVISIBLE (-5248 3250);
FORCEADD TAP..1
R 2
(-5250 3200);
FORCEPROP 3 LASTPIN (-5200 3200) SIG_NAME UPI_CPU1_CPU0_P0P0_DP<8>
J 0
(-5190 3210);
DISPLAY 0.659574 (-5190 3210);
PAINT MONO (-5190 3210);
DISPLAY INVISIBLE (-5190 3210);
FORCEPROP 1 LASTPIN (-5200 3200) BN 8
J 2
(-5188 3208);
DISPLAY 0.617021 (-5188 3208);
PAINT PINK (-5188 3208);
FORCEPROP 2 LAST CDS_LIB mstr_standard
J 0
(-5250 3200);
PAINT MONO (-5250 3200);
DISPLAY INVISIBLE (-5250 3200);
FORCEPROP 1 LAST BODY_TYPE PLUMBING
J 2
(-5250 3250);
DISPLAY 1.446809 (-5250 3250);
PAINT GREEN (-5250 3250);
DISPLAY INVISIBLE (-5250 3250);
FORCEPROP 1 LAST HDL_TAP TRUE
J 2
(-5575 3075);
DISPLAY 1.446809 (-5575 3075);
PAINT GREEN (-5575 3075);
DISPLAY INVISIBLE (-5575 3075);
FORCEPROP 1 LAST PATH I36
J 2
(-5248 3200);
DISPLAY 0.872340 (-5248 3200);
PAINT GREEN (-5248 3200);
DISPLAY INVISIBLE (-5248 3200);
FORCEADD TAP..1
R 2
(-5250 3300);
FORCEPROP 3 LASTPIN (-5200 3300) SIG_NAME UPI_CPU1_CPU0_P0P0_DP<6>
J 0
(-5190 3310);
DISPLAY 0.659574 (-5190 3310);
PAINT MONO (-5190 3310);
DISPLAY INVISIBLE (-5190 3310);
FORCEPROP 1 LASTPIN (-5200 3300) BN 6
J 2
(-5188 3308);
DISPLAY 0.617021 (-5188 3308);
PAINT PINK (-5188 3308);
FORCEPROP 2 LAST CDS_LIB mstr_standard
J 0
(-5250 3300);
PAINT MONO (-5250 3300);
DISPLAY INVISIBLE (-5250 3300);
FORCEPROP 1 LAST BODY_TYPE PLUMBING
J 2
(-5250 3350);
DISPLAY 1.446809 (-5250 3350);
PAINT GREEN (-5250 3350);
DISPLAY INVISIBLE (-5250 3350);
FORCEPROP 1 LAST HDL_TAP TRUE
J 2
(-5575 3175);
DISPLAY 1.446809 (-5575 3175);
PAINT GREEN (-5575 3175);
DISPLAY INVISIBLE (-5575 3175);
FORCEPROP 1 LAST PATH I37
J 2
(-5248 3300);
DISPLAY 0.872340 (-5248 3300);
PAINT GREEN (-5248 3300);
DISPLAY INVISIBLE (-5248 3300);
FORCEADD TAP..1
R 2
(-5250 3400);
FORCEPROP 3 LASTPIN (-5200 3400) SIG_NAME UPI_CPU1_CPU0_P0P0_DP<4>
J 0
(-5190 3410);
DISPLAY 0.659574 (-5190 3410);
PAINT MONO (-5190 3410);
DISPLAY INVISIBLE (-5190 3410);
FORCEPROP 1 LASTPIN (-5200 3400) BN 4
J 2
(-5188 3408);
DISPLAY 0.617021 (-5188 3408);
PAINT PINK (-5188 3408);
FORCEPROP 2 LAST CDS_LIB mstr_standard
J 0
(-5250 3400);
PAINT MONO (-5250 3400);
DISPLAY INVISIBLE (-5250 3400);
FORCEPROP 1 LAST BODY_TYPE PLUMBING
J 2
(-5250 3450);
DISPLAY 1.446809 (-5250 3450);
PAINT GREEN (-5250 3450);
DISPLAY INVISIBLE (-5250 3450);
FORCEPROP 1 LAST HDL_TAP TRUE
J 2
(-5575 3275);
DISPLAY 1.446809 (-5575 3275);
PAINT GREEN (-5575 3275);
DISPLAY INVISIBLE (-5575 3275);
FORCEPROP 1 LAST PATH I38
J 2
(-5248 3400);
DISPLAY 0.872340 (-5248 3400);
PAINT GREEN (-5248 3400);
DISPLAY INVISIBLE (-5248 3400);
FORCEADD TAP..1
R 2
(-5250 3350);
FORCEPROP 3 LASTPIN (-5200 3350) SIG_NAME UPI_CPU1_CPU0_P0P0_DP<5>
J 0
(-5190 3360);
DISPLAY 0.659574 (-5190 3360);
PAINT MONO (-5190 3360);
DISPLAY INVISIBLE (-5190 3360);
FORCEPROP 1 LASTPIN (-5200 3350) BN 5
J 2
(-5188 3358);
DISPLAY 0.617021 (-5188 3358);
PAINT PINK (-5188 3358);
FORCEPROP 2 LAST CDS_LIB mstr_standard
J 0
(-5250 3350);
PAINT MONO (-5250 3350);
DISPLAY INVISIBLE (-5250 3350);
FORCEPROP 1 LAST BODY_TYPE PLUMBING
J 2
(-5250 3400);
DISPLAY 1.446809 (-5250 3400);
PAINT GREEN (-5250 3400);
DISPLAY INVISIBLE (-5250 3400);
FORCEPROP 1 LAST HDL_TAP TRUE
J 2
(-5575 3225);
DISPLAY 1.446809 (-5575 3225);
PAINT GREEN (-5575 3225);
DISPLAY INVISIBLE (-5575 3225);
FORCEPROP 1 LAST PATH I39
J 2
(-5248 3350);
DISPLAY 0.872340 (-5248 3350);
PAINT GREEN (-5248 3350);
DISPLAY INVISIBLE (-5248 3350);
FORCEADD TAP..1
R 2
(-5250 1700);
FORCEPROP 3 LASTPIN (-5200 1700) SIG_NAME UPI_CPU1_CPU0_P0P0_DN<17>
J 0
(-5190 1710);
DISPLAY 0.659574 (-5190 1710);
PAINT MONO (-5190 1710);
DISPLAY INVISIBLE (-5190 1710);
FORCEPROP 1 LASTPIN (-5200 1700) BN 17
J 2
(-5188 1708);
DISPLAY 0.617021 (-5188 1708);
PAINT PINK (-5188 1708);
FORCEPROP 2 LAST CDS_LIB mstr_standard
J 0
(-5250 1700);
PAINT MONO (-5250 1700);
DISPLAY INVISIBLE (-5250 1700);
FORCEPROP 1 LAST BODY_TYPE PLUMBING
J 2
(-5250 1750);
DISPLAY 1.446809 (-5250 1750);
PAINT GREEN (-5250 1750);
DISPLAY INVISIBLE (-5250 1750);
FORCEPROP 1 LAST HDL_TAP TRUE
J 2
(-5575 1575);
DISPLAY 1.446809 (-5575 1575);
PAINT GREEN (-5575 1575);
DISPLAY INVISIBLE (-5575 1575);
FORCEPROP 1 LAST PATH I4
J 2
(-5248 1700);
DISPLAY 0.872340 (-5248 1700);
PAINT GREEN (-5248 1700);
DISPLAY INVISIBLE (-5248 1700);
FORCEADD TAP..1
R 2
(-5250 3500);
FORCEPROP 3 LASTPIN (-5200 3500) SIG_NAME UPI_CPU1_CPU0_P0P0_DP<2>
J 0
(-5190 3510);
DISPLAY 0.659574 (-5190 3510);
PAINT MONO (-5190 3510);
DISPLAY INVISIBLE (-5190 3510);
FORCEPROP 1 LASTPIN (-5200 3500) BN 2
J 2
(-5188 3508);
DISPLAY 0.617021 (-5188 3508);
PAINT PINK (-5188 3508);
FORCEPROP 2 LAST CDS_LIB mstr_standard
J 0
(-5250 3500);
PAINT MONO (-5250 3500);
DISPLAY INVISIBLE (-5250 3500);
FORCEPROP 1 LAST BODY_TYPE PLUMBING
J 2
(-5250 3550);
DISPLAY 1.446809 (-5250 3550);
PAINT GREEN (-5250 3550);
DISPLAY INVISIBLE (-5250 3550);
FORCEPROP 1 LAST HDL_TAP TRUE
J 2
(-5575 3375);
DISPLAY 1.446809 (-5575 3375);
PAINT GREEN (-5575 3375);
DISPLAY INVISIBLE (-5575 3375);
FORCEPROP 1 LAST PATH I40
J 2
(-5248 3500);
DISPLAY 0.872340 (-5248 3500);
PAINT GREEN (-5248 3500);
DISPLAY INVISIBLE (-5248 3500);
FORCEADD TAP..1
R 2
(-5250 3450);
FORCEPROP 3 LASTPIN (-5200 3450) SIG_NAME UPI_CPU1_CPU0_P0P0_DP<3>
J 0
(-5190 3460);
DISPLAY 0.659574 (-5190 3460);
PAINT MONO (-5190 3460);
DISPLAY INVISIBLE (-5190 3460);
FORCEPROP 1 LASTPIN (-5200 3450) BN 3
J 2
(-5188 3458);
DISPLAY 0.617021 (-5188 3458);
PAINT PINK (-5188 3458);
FORCEPROP 2 LAST CDS_LIB mstr_standard
J 0
(-5250 3450);
PAINT MONO (-5250 3450);
DISPLAY INVISIBLE (-5250 3450);
FORCEPROP 1 LAST BODY_TYPE PLUMBING
J 2
(-5250 3500);
DISPLAY 1.446809 (-5250 3500);
PAINT GREEN (-5250 3500);
DISPLAY INVISIBLE (-5250 3500);
FORCEPROP 1 LAST HDL_TAP TRUE
J 2
(-5575 3325);
DISPLAY 1.446809 (-5575 3325);
PAINT GREEN (-5575 3325);
DISPLAY INVISIBLE (-5575 3325);
FORCEPROP 1 LAST PATH I41
J 2
(-5248 3450);
DISPLAY 0.872340 (-5248 3450);
PAINT GREEN (-5248 3450);
DISPLAY INVISIBLE (-5248 3450);
FORCEADD TAP..1
R 2
(-5250 3550);
FORCEPROP 3 LASTPIN (-5200 3550) SIG_NAME UPI_CPU1_CPU0_P0P0_DP<1>
J 0
(-5190 3560);
DISPLAY 0.659574 (-5190 3560);
PAINT MONO (-5190 3560);
DISPLAY INVISIBLE (-5190 3560);
FORCEPROP 1 LASTPIN (-5200 3550) BN 1
J 2
(-5188 3558);
DISPLAY 0.617021 (-5188 3558);
PAINT PINK (-5188 3558);
FORCEPROP 2 LAST CDS_LIB mstr_standard
J 0
(-5250 3550);
PAINT MONO (-5250 3550);
DISPLAY INVISIBLE (-5250 3550);
FORCEPROP 1 LAST BODY_TYPE PLUMBING
J 2
(-5250 3600);
DISPLAY 1.446809 (-5250 3600);
PAINT GREEN (-5250 3600);
DISPLAY INVISIBLE (-5250 3600);
FORCEPROP 1 LAST HDL_TAP TRUE
J 2
(-5575 3425);
DISPLAY 1.446809 (-5575 3425);
PAINT GREEN (-5575 3425);
DISPLAY INVISIBLE (-5575 3425);
FORCEPROP 1 LAST PATH I42
J 2
(-5248 3550);
DISPLAY 0.872340 (-5248 3550);
PAINT GREEN (-5248 3550);
DISPLAY INVISIBLE (-5248 3550);
FORCEADD TAP..1
R 2
(-5250 3600);
FORCEPROP 3 LASTPIN (-5200 3600) SIG_NAME UPI_CPU1_CPU0_P0P0_DP<0>
J 0
(-5190 3610);
DISPLAY 0.659574 (-5190 3610);
PAINT MONO (-5190 3610);
DISPLAY INVISIBLE (-5190 3610);
FORCEPROP 1 LASTPIN (-5200 3600) BN 0
J 2
(-5188 3608);
DISPLAY 0.617021 (-5188 3608);
PAINT PINK (-5188 3608);
FORCEPROP 2 LAST CDS_LIB mstr_standard
J 0
(-5250 3600);
PAINT MONO (-5250 3600);
DISPLAY INVISIBLE (-5250 3600);
FORCEPROP 1 LAST BODY_TYPE PLUMBING
J 2
(-5250 3650);
DISPLAY 1.446809 (-5250 3650);
PAINT GREEN (-5250 3650);
DISPLAY INVISIBLE (-5250 3650);
FORCEPROP 1 LAST HDL_TAP TRUE
J 2
(-5575 3475);
DISPLAY 1.446809 (-5575 3475);
PAINT GREEN (-5575 3475);
DISPLAY INVISIBLE (-5575 3475);
FORCEPROP 1 LAST PATH I43
J 2
(-5248 3600);
DISPLAY 0.872340 (-5248 3600);
PAINT GREEN (-5248 3600);
DISPLAY INVISIBLE (-5248 3600);
FORCEADD TAP..1
(-2925 1600);
FORCEPROP 3 LASTPIN (-2975 1600) SIG_NAME UPI_CPU0_CPU1_P0P0_DN<19>
J 0
(-2965 1610);
DISPLAY 0.659574 (-2965 1610);
PAINT MONO (-2965 1610);
DISPLAY INVISIBLE (-2965 1610);
FORCEPROP 1 LASTPIN (-2975 1600) BN 19
J 0
(-2987 1608);
DISPLAY 0.617021 (-2987 1608);
PAINT PINK (-2987 1608);
FORCEPROP 2 LAST CDS_LIB mstr_standard
J 0
(-2925 1600);
PAINT MONO (-2925 1600);
DISPLAY INVISIBLE (-2925 1600);
FORCEPROP 1 LAST BODY_TYPE PLUMBING
J 0
(-2925 1650);
DISPLAY 1.446809 (-2925 1650);
PAINT GREEN (-2925 1650);
DISPLAY INVISIBLE (-2925 1650);
FORCEPROP 1 LAST HDL_TAP TRUE
J 0
(-2600 1475);
DISPLAY 1.446809 (-2600 1475);
PAINT GREEN (-2600 1475);
DISPLAY INVISIBLE (-2600 1475);
FORCEPROP 1 LAST PATH I44
J 0
(-2927 1600);
DISPLAY 0.872340 (-2927 1600);
PAINT GREEN (-2927 1600);
DISPLAY INVISIBLE (-2927 1600);
FORCEADD TAP..1
(-2925 1750);
FORCEPROP 3 LASTPIN (-2975 1750) SIG_NAME UPI_CPU0_CPU1_P0P0_DN<16>
J 0
(-2965 1760);
DISPLAY 0.659574 (-2965 1760);
PAINT MONO (-2965 1760);
DISPLAY INVISIBLE (-2965 1760);
FORCEPROP 1 LASTPIN (-2975 1750) BN 16
J 0
(-2987 1758);
DISPLAY 0.617021 (-2987 1758);
PAINT PINK (-2987 1758);
FORCEPROP 2 LAST CDS_LIB mstr_standard
J 0
(-2925 1750);
PAINT MONO (-2925 1750);
DISPLAY INVISIBLE (-2925 1750);
FORCEPROP 1 LAST BODY_TYPE PLUMBING
J 0
(-2925 1800);
DISPLAY 1.446809 (-2925 1800);
PAINT GREEN (-2925 1800);
DISPLAY INVISIBLE (-2925 1800);
FORCEPROP 1 LAST HDL_TAP TRUE
J 0
(-2600 1625);
DISPLAY 1.446809 (-2600 1625);
PAINT GREEN (-2600 1625);
DISPLAY INVISIBLE (-2600 1625);
FORCEPROP 1 LAST PATH I45
J 0
(-2927 1750);
DISPLAY 0.872340 (-2927 1750);
PAINT GREEN (-2927 1750);
DISPLAY INVISIBLE (-2927 1750);
FORCEADD TAP..1
(-2925 1700);
FORCEPROP 3 LASTPIN (-2975 1700) SIG_NAME UPI_CPU0_CPU1_P0P0_DN<17>
J 0
(-2965 1710);
DISPLAY 0.659574 (-2965 1710);
PAINT MONO (-2965 1710);
DISPLAY INVISIBLE (-2965 1710);
FORCEPROP 1 LASTPIN (-2975 1700) BN 17
J 0
(-2987 1708);
DISPLAY 0.617021 (-2987 1708);
PAINT PINK (-2987 1708);
FORCEPROP 2 LAST CDS_LIB mstr_standard
J 0
(-2925 1700);
PAINT MONO (-2925 1700);
DISPLAY INVISIBLE (-2925 1700);
FORCEPROP 1 LAST BODY_TYPE PLUMBING
J 0
(-2925 1750);
DISPLAY 1.446809 (-2925 1750);
PAINT GREEN (-2925 1750);
DISPLAY INVISIBLE (-2925 1750);
FORCEPROP 1 LAST HDL_TAP TRUE
J 0
(-2600 1575);
DISPLAY 1.446809 (-2600 1575);
PAINT GREEN (-2600 1575);
DISPLAY INVISIBLE (-2600 1575);
FORCEPROP 1 LAST PATH I46
J 0
(-2927 1700);
DISPLAY 0.872340 (-2927 1700);
PAINT GREEN (-2927 1700);
DISPLAY INVISIBLE (-2927 1700);
FORCEADD TAP..1
(-2925 1650);
FORCEPROP 3 LASTPIN (-2975 1650) SIG_NAME UPI_CPU0_CPU1_P0P0_DN<18>
J 0
(-2965 1660);
DISPLAY 0.659574 (-2965 1660);
PAINT MONO (-2965 1660);
DISPLAY INVISIBLE (-2965 1660);
FORCEPROP 1 LASTPIN (-2975 1650) BN 18
J 0
(-2987 1658);
DISPLAY 0.617021 (-2987 1658);
PAINT PINK (-2987 1658);
FORCEPROP 2 LAST CDS_LIB mstr_standard
J 0
(-2925 1650);
PAINT MONO (-2925 1650);
DISPLAY INVISIBLE (-2925 1650);
FORCEPROP 1 LAST BODY_TYPE PLUMBING
J 0
(-2925 1700);
DISPLAY 1.446809 (-2925 1700);
PAINT GREEN (-2925 1700);
DISPLAY INVISIBLE (-2925 1700);
FORCEPROP 1 LAST HDL_TAP TRUE
J 0
(-2600 1525);
DISPLAY 1.446809 (-2600 1525);
PAINT GREEN (-2600 1525);
DISPLAY INVISIBLE (-2600 1525);
FORCEPROP 1 LAST PATH I47
J 0
(-2927 1650);
DISPLAY 0.872340 (-2927 1650);
PAINT GREEN (-2927 1650);
DISPLAY INVISIBLE (-2927 1650);
FORCEADD TAP..1
(-2925 1850);
FORCEPROP 3 LASTPIN (-2975 1850) SIG_NAME UPI_CPU0_CPU1_P0P0_DN<14>
J 0
(-2965 1860);
DISPLAY 0.659574 (-2965 1860);
PAINT MONO (-2965 1860);
DISPLAY INVISIBLE (-2965 1860);
FORCEPROP 1 LASTPIN (-2975 1850) BN 14
J 0
(-2987 1858);
DISPLAY 0.617021 (-2987 1858);
PAINT PINK (-2987 1858);
FORCEPROP 2 LAST CDS_LIB mstr_standard
J 0
(-2925 1850);
PAINT MONO (-2925 1850);
DISPLAY INVISIBLE (-2925 1850);
FORCEPROP 1 LAST BODY_TYPE PLUMBING
J 0
(-2925 1900);
DISPLAY 1.446809 (-2925 1900);
PAINT GREEN (-2925 1900);
DISPLAY INVISIBLE (-2925 1900);
FORCEPROP 1 LAST HDL_TAP TRUE
J 0
(-2600 1725);
DISPLAY 1.446809 (-2600 1725);
PAINT GREEN (-2600 1725);
DISPLAY INVISIBLE (-2600 1725);
FORCEPROP 1 LAST PATH I48
J 0
(-2927 1850);
DISPLAY 0.872340 (-2927 1850);
PAINT GREEN (-2927 1850);
DISPLAY INVISIBLE (-2927 1850);
FORCEADD TAP..1
(-2925 1800);
FORCEPROP 3 LASTPIN (-2975 1800) SIG_NAME UPI_CPU0_CPU1_P0P0_DN<15>
J 0
(-2965 1810);
DISPLAY 0.659574 (-2965 1810);
PAINT MONO (-2965 1810);
DISPLAY INVISIBLE (-2965 1810);
FORCEPROP 1 LASTPIN (-2975 1800) BN 15
J 0
(-2987 1808);
DISPLAY 0.617021 (-2987 1808);
PAINT PINK (-2987 1808);
FORCEPROP 2 LAST CDS_LIB mstr_standard
J 0
(-2925 1800);
PAINT MONO (-2925 1800);
DISPLAY INVISIBLE (-2925 1800);
FORCEPROP 1 LAST BODY_TYPE PLUMBING
J 0
(-2925 1850);
DISPLAY 1.446809 (-2925 1850);
PAINT GREEN (-2925 1850);
DISPLAY INVISIBLE (-2925 1850);
FORCEPROP 1 LAST HDL_TAP TRUE
J 0
(-2600 1675);
DISPLAY 1.446809 (-2600 1675);
PAINT GREEN (-2600 1675);
DISPLAY INVISIBLE (-2600 1675);
FORCEPROP 1 LAST PATH I49
J 0
(-2927 1800);
DISPLAY 0.872340 (-2927 1800);
PAINT GREEN (-2927 1800);
DISPLAY INVISIBLE (-2927 1800);
FORCEADD TAP..1
R 2
(-5250 1650);
FORCEPROP 3 LASTPIN (-5200 1650) SIG_NAME UPI_CPU1_CPU0_P0P0_DN<18>
J 0
(-5190 1660);
DISPLAY 0.659574 (-5190 1660);
PAINT MONO (-5190 1660);
DISPLAY INVISIBLE (-5190 1660);
FORCEPROP 1 LASTPIN (-5200 1650) BN 18
J 2
(-5188 1658);
DISPLAY 0.617021 (-5188 1658);
PAINT PINK (-5188 1658);
FORCEPROP 2 LAST CDS_LIB mstr_standard
J 0
(-5250 1650);
PAINT MONO (-5250 1650);
DISPLAY INVISIBLE (-5250 1650);
FORCEPROP 1 LAST BODY_TYPE PLUMBING
J 2
(-5250 1700);
DISPLAY 1.446809 (-5250 1700);
PAINT GREEN (-5250 1700);
DISPLAY INVISIBLE (-5250 1700);
FORCEPROP 1 LAST HDL_TAP TRUE
J 2
(-5575 1525);
DISPLAY 1.446809 (-5575 1525);
PAINT GREEN (-5575 1525);
DISPLAY INVISIBLE (-5575 1525);
FORCEPROP 1 LAST PATH I5
J 2
(-5248 1650);
DISPLAY 0.872340 (-5248 1650);
PAINT GREEN (-5248 1650);
DISPLAY INVISIBLE (-5248 1650);
FORCEADD TAP..1
(-2925 1900);
FORCEPROP 3 LASTPIN (-2975 1900) SIG_NAME UPI_CPU0_CPU1_P0P0_DN<13>
J 0
(-2965 1910);
DISPLAY 0.659574 (-2965 1910);
PAINT MONO (-2965 1910);
DISPLAY INVISIBLE (-2965 1910);
FORCEPROP 1 LASTPIN (-2975 1900) BN 13
J 0
(-2987 1908);
DISPLAY 0.617021 (-2987 1908);
PAINT PINK (-2987 1908);
FORCEPROP 2 LAST CDS_LIB mstr_standard
J 0
(-2925 1900);
PAINT MONO (-2925 1900);
DISPLAY INVISIBLE (-2925 1900);
FORCEPROP 1 LAST BODY_TYPE PLUMBING
J 0
(-2925 1950);
DISPLAY 1.446809 (-2925 1950);
PAINT GREEN (-2925 1950);
DISPLAY INVISIBLE (-2925 1950);
FORCEPROP 1 LAST HDL_TAP TRUE
J 0
(-2600 1775);
DISPLAY 1.446809 (-2600 1775);
PAINT GREEN (-2600 1775);
DISPLAY INVISIBLE (-2600 1775);
FORCEPROP 1 LAST PATH I50
J 0
(-2927 1900);
DISPLAY 0.872340 (-2927 1900);
PAINT GREEN (-2927 1900);
DISPLAY INVISIBLE (-2927 1900);
FORCEADD TAP..1
(-2925 2000);
FORCEPROP 3 LASTPIN (-2975 2000) SIG_NAME UPI_CPU0_CPU1_P0P0_DN<11>
J 0
(-2965 2010);
DISPLAY 0.659574 (-2965 2010);
PAINT MONO (-2965 2010);
DISPLAY INVISIBLE (-2965 2010);
FORCEPROP 1 LASTPIN (-2975 2000) BN 11
J 0
(-2987 2008);
DISPLAY 0.617021 (-2987 2008);
PAINT PINK (-2987 2008);
FORCEPROP 2 LAST CDS_LIB mstr_standard
J 0
(-2925 2000);
PAINT MONO (-2925 2000);
DISPLAY INVISIBLE (-2925 2000);
FORCEPROP 1 LAST BODY_TYPE PLUMBING
J 0
(-2925 2050);
DISPLAY 1.446809 (-2925 2050);
PAINT GREEN (-2925 2050);
DISPLAY INVISIBLE (-2925 2050);
FORCEPROP 1 LAST HDL_TAP TRUE
J 0
(-2600 1875);
DISPLAY 1.446809 (-2600 1875);
PAINT GREEN (-2600 1875);
DISPLAY INVISIBLE (-2600 1875);
FORCEPROP 1 LAST PATH I51
J 0
(-2927 2000);
DISPLAY 0.872340 (-2927 2000);
PAINT GREEN (-2927 2000);
DISPLAY INVISIBLE (-2927 2000);
FORCEADD TAP..1
(-2925 1950);
FORCEPROP 3 LASTPIN (-2975 1950) SIG_NAME UPI_CPU0_CPU1_P0P0_DN<12>
J 0
(-2965 1960);
DISPLAY 0.659574 (-2965 1960);
PAINT MONO (-2965 1960);
DISPLAY INVISIBLE (-2965 1960);
FORCEPROP 1 LASTPIN (-2975 1950) BN 12
J 0
(-2987 1958);
DISPLAY 0.617021 (-2987 1958);
PAINT PINK (-2987 1958);
FORCEPROP 2 LAST CDS_LIB mstr_standard
J 0
(-2925 1950);
PAINT MONO (-2925 1950);
DISPLAY INVISIBLE (-2925 1950);
FORCEPROP 1 LAST BODY_TYPE PLUMBING
J 0
(-2925 2000);
DISPLAY 1.446809 (-2925 2000);
PAINT GREEN (-2925 2000);
DISPLAY INVISIBLE (-2925 2000);
FORCEPROP 1 LAST HDL_TAP TRUE
J 0
(-2600 1825);
DISPLAY 1.446809 (-2600 1825);
PAINT GREEN (-2600 1825);
DISPLAY INVISIBLE (-2600 1825);
FORCEPROP 1 LAST PATH I52
J 0
(-2927 1950);
DISPLAY 0.872340 (-2927 1950);
PAINT GREEN (-2927 1950);
DISPLAY INVISIBLE (-2927 1950);
FORCEADD TAP..1
(-2925 2150);
FORCEPROP 3 LASTPIN (-2975 2150) SIG_NAME UPI_CPU0_CPU1_P0P0_DN<8>
J 0
(-2965 2160);
DISPLAY 0.659574 (-2965 2160);
PAINT MONO (-2965 2160);
DISPLAY INVISIBLE (-2965 2160);
FORCEPROP 1 LASTPIN (-2975 2150) BN 8
J 0
(-2987 2158);
DISPLAY 0.617021 (-2987 2158);
PAINT PINK (-2987 2158);
FORCEPROP 2 LAST CDS_LIB mstr_standard
J 0
(-2925 2150);
PAINT MONO (-2925 2150);
DISPLAY INVISIBLE (-2925 2150);
FORCEPROP 1 LAST BODY_TYPE PLUMBING
J 0
(-2925 2200);
DISPLAY 1.446809 (-2925 2200);
PAINT GREEN (-2925 2200);
DISPLAY INVISIBLE (-2925 2200);
FORCEPROP 1 LAST HDL_TAP TRUE
J 0
(-2600 2025);
DISPLAY 1.446809 (-2600 2025);
PAINT GREEN (-2600 2025);
DISPLAY INVISIBLE (-2600 2025);
FORCEPROP 1 LAST PATH I53
J 0
(-2927 2150);
DISPLAY 0.872340 (-2927 2150);
PAINT GREEN (-2927 2150);
DISPLAY INVISIBLE (-2927 2150);
FORCEADD TAP..1
(-2925 2100);
FORCEPROP 3 LASTPIN (-2975 2100) SIG_NAME UPI_CPU0_CPU1_P0P0_DN<9>
J 0
(-2965 2110);
DISPLAY 0.659574 (-2965 2110);
PAINT MONO (-2965 2110);
DISPLAY INVISIBLE (-2965 2110);
FORCEPROP 1 LASTPIN (-2975 2100) BN 9
J 0
(-2987 2108);
DISPLAY 0.617021 (-2987 2108);
PAINT PINK (-2987 2108);
FORCEPROP 2 LAST CDS_LIB mstr_standard
J 0
(-2925 2100);
PAINT MONO (-2925 2100);
DISPLAY INVISIBLE (-2925 2100);
FORCEPROP 1 LAST BODY_TYPE PLUMBING
J 0
(-2925 2150);
DISPLAY 1.446809 (-2925 2150);
PAINT GREEN (-2925 2150);
DISPLAY INVISIBLE (-2925 2150);
FORCEPROP 1 LAST HDL_TAP TRUE
J 0
(-2600 1975);
DISPLAY 1.446809 (-2600 1975);
PAINT GREEN (-2600 1975);
DISPLAY INVISIBLE (-2600 1975);
FORCEPROP 1 LAST PATH I54
J 0
(-2927 2100);
DISPLAY 0.872340 (-2927 2100);
PAINT GREEN (-2927 2100);
DISPLAY INVISIBLE (-2927 2100);
FORCEADD TAP..1
(-2925 2050);
FORCEPROP 3 LASTPIN (-2975 2050) SIG_NAME UPI_CPU0_CPU1_P0P0_DN<10>
J 0
(-2965 2060);
DISPLAY 0.659574 (-2965 2060);
PAINT MONO (-2965 2060);
DISPLAY INVISIBLE (-2965 2060);
FORCEPROP 1 LASTPIN (-2975 2050) BN 10
J 0
(-2987 2058);
DISPLAY 0.617021 (-2987 2058);
PAINT PINK (-2987 2058);
FORCEPROP 2 LAST CDS_LIB mstr_standard
J 0
(-2925 2050);
PAINT MONO (-2925 2050);
DISPLAY INVISIBLE (-2925 2050);
FORCEPROP 1 LAST BODY_TYPE PLUMBING
J 0
(-2925 2100);
DISPLAY 1.446809 (-2925 2100);
PAINT GREEN (-2925 2100);
DISPLAY INVISIBLE (-2925 2100);
FORCEPROP 1 LAST HDL_TAP TRUE
J 0
(-2600 1925);
DISPLAY 1.446809 (-2600 1925);
PAINT GREEN (-2600 1925);
DISPLAY INVISIBLE (-2600 1925);
FORCEPROP 1 LAST PATH I55
J 0
(-2927 2050);
DISPLAY 0.872340 (-2927 2050);
PAINT GREEN (-2927 2050);
DISPLAY INVISIBLE (-2927 2050);
FORCEADD TAP..1
(-2925 2250);
FORCEPROP 3 LASTPIN (-2975 2250) SIG_NAME UPI_CPU0_CPU1_P0P0_DN<6>
J 0
(-2965 2260);
DISPLAY 0.659574 (-2965 2260);
PAINT MONO (-2965 2260);
DISPLAY INVISIBLE (-2965 2260);
FORCEPROP 1 LASTPIN (-2975 2250) BN 6
J 0
(-2987 2258);
DISPLAY 0.617021 (-2987 2258);
PAINT PINK (-2987 2258);
FORCEPROP 2 LAST CDS_LIB mstr_standard
J 0
(-2925 2250);
PAINT MONO (-2925 2250);
DISPLAY INVISIBLE (-2925 2250);
FORCEPROP 1 LAST BODY_TYPE PLUMBING
J 0
(-2925 2300);
DISPLAY 1.446809 (-2925 2300);
PAINT GREEN (-2925 2300);
DISPLAY INVISIBLE (-2925 2300);
FORCEPROP 1 LAST HDL_TAP TRUE
J 0
(-2600 2125);
DISPLAY 1.446809 (-2600 2125);
PAINT GREEN (-2600 2125);
DISPLAY INVISIBLE (-2600 2125);
FORCEPROP 1 LAST PATH I56
J 0
(-2927 2250);
DISPLAY 0.872340 (-2927 2250);
PAINT GREEN (-2927 2250);
DISPLAY INVISIBLE (-2927 2250);
FORCEADD TAP..1
(-2925 2200);
FORCEPROP 3 LASTPIN (-2975 2200) SIG_NAME UPI_CPU0_CPU1_P0P0_DN<7>
J 0
(-2965 2210);
DISPLAY 0.659574 (-2965 2210);
PAINT MONO (-2965 2210);
DISPLAY INVISIBLE (-2965 2210);
FORCEPROP 1 LASTPIN (-2975 2200) BN 7
J 0
(-2987 2208);
DISPLAY 0.617021 (-2987 2208);
PAINT PINK (-2987 2208);
FORCEPROP 2 LAST CDS_LIB mstr_standard
J 0
(-2925 2200);
PAINT MONO (-2925 2200);
DISPLAY INVISIBLE (-2925 2200);
FORCEPROP 1 LAST BODY_TYPE PLUMBING
J 0
(-2925 2250);
DISPLAY 1.446809 (-2925 2250);
PAINT GREEN (-2925 2250);
DISPLAY INVISIBLE (-2925 2250);
FORCEPROP 1 LAST HDL_TAP TRUE
J 0
(-2600 2075);
DISPLAY 1.446809 (-2600 2075);
PAINT GREEN (-2600 2075);
DISPLAY INVISIBLE (-2600 2075);
FORCEPROP 1 LAST PATH I57
J 0
(-2927 2200);
DISPLAY 0.872340 (-2927 2200);
PAINT GREEN (-2927 2200);
DISPLAY INVISIBLE (-2927 2200);
FORCEADD TAP..1
(-2925 2300);
FORCEPROP 3 LASTPIN (-2975 2300) SIG_NAME UPI_CPU0_CPU1_P0P0_DN<5>
J 0
(-2965 2310);
DISPLAY 0.659574 (-2965 2310);
PAINT MONO (-2965 2310);
DISPLAY INVISIBLE (-2965 2310);
FORCEPROP 1 LASTPIN (-2975 2300) BN 5
J 0
(-2987 2308);
DISPLAY 0.617021 (-2987 2308);
PAINT PINK (-2987 2308);
FORCEPROP 2 LAST CDS_LIB mstr_standard
J 0
(-2925 2300);
PAINT MONO (-2925 2300);
DISPLAY INVISIBLE (-2925 2300);
FORCEPROP 1 LAST BODY_TYPE PLUMBING
J 0
(-2925 2350);
DISPLAY 1.446809 (-2925 2350);
PAINT GREEN (-2925 2350);
DISPLAY INVISIBLE (-2925 2350);
FORCEPROP 1 LAST HDL_TAP TRUE
J 0
(-2600 2175);
DISPLAY 1.446809 (-2600 2175);
PAINT GREEN (-2600 2175);
DISPLAY INVISIBLE (-2600 2175);
FORCEPROP 1 LAST PATH I58
J 0
(-2927 2300);
DISPLAY 0.872340 (-2927 2300);
PAINT GREEN (-2927 2300);
DISPLAY INVISIBLE (-2927 2300);
FORCEADD TAP..1
(-2925 2400);
FORCEPROP 3 LASTPIN (-2975 2400) SIG_NAME UPI_CPU0_CPU1_P0P0_DN<3>
J 0
(-2965 2410);
DISPLAY 0.659574 (-2965 2410);
PAINT MONO (-2965 2410);
DISPLAY INVISIBLE (-2965 2410);
FORCEPROP 1 LASTPIN (-2975 2400) BN 3
J 0
(-2987 2408);
DISPLAY 0.617021 (-2987 2408);
PAINT PINK (-2987 2408);
FORCEPROP 2 LAST CDS_LIB mstr_standard
J 0
(-2925 2400);
PAINT MONO (-2925 2400);
DISPLAY INVISIBLE (-2925 2400);
FORCEPROP 1 LAST BODY_TYPE PLUMBING
J 0
(-2925 2450);
DISPLAY 1.446809 (-2925 2450);
PAINT GREEN (-2925 2450);
DISPLAY INVISIBLE (-2925 2450);
FORCEPROP 1 LAST HDL_TAP TRUE
J 0
(-2600 2275);
DISPLAY 1.446809 (-2600 2275);
PAINT GREEN (-2600 2275);
DISPLAY INVISIBLE (-2600 2275);
FORCEPROP 1 LAST PATH I59
J 0
(-2927 2400);
DISPLAY 0.872340 (-2927 2400);
PAINT GREEN (-2927 2400);
DISPLAY INVISIBLE (-2927 2400);
FORCEADD TAP..1
R 2
(-5250 1750);
FORCEPROP 3 LASTPIN (-5200 1750) SIG_NAME UPI_CPU1_CPU0_P0P0_DN<16>
J 0
(-5190 1760);
DISPLAY 0.659574 (-5190 1760);
PAINT MONO (-5190 1760);
DISPLAY INVISIBLE (-5190 1760);
FORCEPROP 1 LASTPIN (-5200 1750) BN 16
J 2
(-5188 1758);
DISPLAY 0.617021 (-5188 1758);
PAINT PINK (-5188 1758);
FORCEPROP 2 LAST CDS_LIB mstr_standard
J 0
(-5250 1750);
PAINT MONO (-5250 1750);
DISPLAY INVISIBLE (-5250 1750);
FORCEPROP 1 LAST BODY_TYPE PLUMBING
J 2
(-5250 1800);
DISPLAY 1.446809 (-5250 1800);
PAINT GREEN (-5250 1800);
DISPLAY INVISIBLE (-5250 1800);
FORCEPROP 1 LAST HDL_TAP TRUE
J 2
(-5575 1625);
DISPLAY 1.446809 (-5575 1625);
PAINT GREEN (-5575 1625);
DISPLAY INVISIBLE (-5575 1625);
FORCEPROP 1 LAST PATH I6
J 2
(-5248 1750);
DISPLAY 0.872340 (-5248 1750);
PAINT GREEN (-5248 1750);
DISPLAY INVISIBLE (-5248 1750);
FORCEADD TAP..1
(-2925 2350);
FORCEPROP 3 LASTPIN (-2975 2350) SIG_NAME UPI_CPU0_CPU1_P0P0_DN<4>
J 0
(-2965 2360);
DISPLAY 0.659574 (-2965 2360);
PAINT MONO (-2965 2360);
DISPLAY INVISIBLE (-2965 2360);
FORCEPROP 1 LASTPIN (-2975 2350) BN 4
J 0
(-2987 2358);
DISPLAY 0.617021 (-2987 2358);
PAINT PINK (-2987 2358);
FORCEPROP 2 LAST CDS_LIB mstr_standard
J 0
(-2925 2350);
PAINT MONO (-2925 2350);
DISPLAY INVISIBLE (-2925 2350);
FORCEPROP 1 LAST BODY_TYPE PLUMBING
J 0
(-2925 2400);
DISPLAY 1.446809 (-2925 2400);
PAINT GREEN (-2925 2400);
DISPLAY INVISIBLE (-2925 2400);
FORCEPROP 1 LAST HDL_TAP TRUE
J 0
(-2600 2225);
DISPLAY 1.446809 (-2600 2225);
PAINT GREEN (-2600 2225);
DISPLAY INVISIBLE (-2600 2225);
FORCEPROP 1 LAST PATH I60
J 0
(-2927 2350);
DISPLAY 0.872340 (-2927 2350);
PAINT GREEN (-2927 2350);
DISPLAY INVISIBLE (-2927 2350);
FORCEADD TAP..1
(-2925 2450);
FORCEPROP 3 LASTPIN (-2975 2450) SIG_NAME UPI_CPU0_CPU1_P0P0_DN<2>
J 0
(-2965 2460);
DISPLAY 0.659574 (-2965 2460);
PAINT MONO (-2965 2460);
DISPLAY INVISIBLE (-2965 2460);
FORCEPROP 1 LASTPIN (-2975 2450) BN 2
J 0
(-2987 2458);
DISPLAY 0.617021 (-2987 2458);
PAINT PINK (-2987 2458);
FORCEPROP 2 LAST CDS_LIB mstr_standard
J 0
(-2925 2450);
PAINT MONO (-2925 2450);
DISPLAY INVISIBLE (-2925 2450);
FORCEPROP 1 LAST BODY_TYPE PLUMBING
J 0
(-2925 2500);
DISPLAY 1.446809 (-2925 2500);
PAINT GREEN (-2925 2500);
DISPLAY INVISIBLE (-2925 2500);
FORCEPROP 1 LAST HDL_TAP TRUE
J 0
(-2600 2325);
DISPLAY 1.446809 (-2600 2325);
PAINT GREEN (-2600 2325);
DISPLAY INVISIBLE (-2600 2325);
FORCEPROP 1 LAST PATH I61
J 0
(-2927 2450);
DISPLAY 0.872340 (-2927 2450);
PAINT GREEN (-2927 2450);
DISPLAY INVISIBLE (-2927 2450);
FORCEADD TAP..1
(-2925 2500);
FORCEPROP 3 LASTPIN (-2975 2500) SIG_NAME UPI_CPU0_CPU1_P0P0_DN<1>
J 0
(-2965 2510);
DISPLAY 0.659574 (-2965 2510);
PAINT MONO (-2965 2510);
DISPLAY INVISIBLE (-2965 2510);
FORCEPROP 1 LASTPIN (-2975 2500) BN 1
J 0
(-2987 2508);
DISPLAY 0.617021 (-2987 2508);
PAINT PINK (-2987 2508);
FORCEPROP 2 LAST CDS_LIB mstr_standard
J 0
(-2925 2500);
PAINT MONO (-2925 2500);
DISPLAY INVISIBLE (-2925 2500);
FORCEPROP 1 LAST BODY_TYPE PLUMBING
J 0
(-2925 2550);
DISPLAY 1.446809 (-2925 2550);
PAINT GREEN (-2925 2550);
DISPLAY INVISIBLE (-2925 2550);
FORCEPROP 1 LAST HDL_TAP TRUE
J 0
(-2600 2375);
DISPLAY 1.446809 (-2600 2375);
PAINT GREEN (-2600 2375);
DISPLAY INVISIBLE (-2600 2375);
FORCEPROP 1 LAST PATH I62
J 0
(-2927 2500);
DISPLAY 0.872340 (-2927 2500);
PAINT GREEN (-2927 2500);
DISPLAY INVISIBLE (-2927 2500);
FORCEADD TAP..1
(-2925 2550);
FORCEPROP 3 LASTPIN (-2975 2550) SIG_NAME UPI_CPU0_CPU1_P0P0_DN<0>
J 0
(-2965 2560);
DISPLAY 0.659574 (-2965 2560);
PAINT MONO (-2965 2560);
DISPLAY INVISIBLE (-2965 2560);
FORCEPROP 1 LASTPIN (-2975 2550) BN 0
J 0
(-2987 2558);
DISPLAY 0.617021 (-2987 2558);
PAINT PINK (-2987 2558);
FORCEPROP 2 LAST CDS_LIB mstr_standard
J 0
(-2925 2550);
PAINT MONO (-2925 2550);
DISPLAY INVISIBLE (-2925 2550);
FORCEPROP 1 LAST BODY_TYPE PLUMBING
J 0
(-2925 2600);
DISPLAY 1.446809 (-2925 2600);
PAINT GREEN (-2925 2600);
DISPLAY INVISIBLE (-2925 2600);
FORCEPROP 1 LAST HDL_TAP TRUE
J 0
(-2600 2425);
DISPLAY 1.446809 (-2600 2425);
PAINT GREEN (-2600 2425);
DISPLAY INVISIBLE (-2600 2425);
FORCEPROP 1 LAST PATH I63
J 0
(-2927 2550);
DISPLAY 0.872340 (-2927 2550);
PAINT GREEN (-2927 2550);
DISPLAY INVISIBLE (-2927 2550);
FORCEADD TAP..1
(-2925 2650);
FORCEPROP 3 LASTPIN (-2975 2650) SIG_NAME UPI_CPU0_CPU1_P0P0_DP<19>
J 0
(-2965 2660);
DISPLAY 0.659574 (-2965 2660);
PAINT MONO (-2965 2660);
DISPLAY INVISIBLE (-2965 2660);
FORCEPROP 1 LASTPIN (-2975 2650) BN 19
J 0
(-2987 2658);
DISPLAY 0.617021 (-2987 2658);
PAINT PINK (-2987 2658);
FORCEPROP 2 LAST CDS_LIB mstr_standard
J 0
(-2925 2650);
PAINT MONO (-2925 2650);
DISPLAY INVISIBLE (-2925 2650);
FORCEPROP 1 LAST BODY_TYPE PLUMBING
J 0
(-2925 2700);
DISPLAY 1.446809 (-2925 2700);
PAINT GREEN (-2925 2700);
DISPLAY INVISIBLE (-2925 2700);
FORCEPROP 1 LAST HDL_TAP TRUE
J 0
(-2600 2525);
DISPLAY 1.446809 (-2600 2525);
PAINT GREEN (-2600 2525);
DISPLAY INVISIBLE (-2600 2525);
FORCEPROP 1 LAST PATH I64
J 0
(-2927 2650);
DISPLAY 0.872340 (-2927 2650);
PAINT GREEN (-2927 2650);
DISPLAY INVISIBLE (-2927 2650);
FORCEADD TAP..1
(-2925 2750);
FORCEPROP 3 LASTPIN (-2975 2750) SIG_NAME UPI_CPU0_CPU1_P0P0_DP<17>
J 0
(-2965 2760);
DISPLAY 0.659574 (-2965 2760);
PAINT MONO (-2965 2760);
DISPLAY INVISIBLE (-2965 2760);
FORCEPROP 1 LASTPIN (-2975 2750) BN 17
J 0
(-2987 2758);
DISPLAY 0.617021 (-2987 2758);
PAINT PINK (-2987 2758);
FORCEPROP 2 LAST CDS_LIB mstr_standard
J 0
(-2925 2750);
PAINT MONO (-2925 2750);
DISPLAY INVISIBLE (-2925 2750);
FORCEPROP 1 LAST BODY_TYPE PLUMBING
J 0
(-2925 2800);
DISPLAY 1.446809 (-2925 2800);
PAINT GREEN (-2925 2800);
DISPLAY INVISIBLE (-2925 2800);
FORCEPROP 1 LAST HDL_TAP TRUE
J 0
(-2600 2625);
DISPLAY 1.446809 (-2600 2625);
PAINT GREEN (-2600 2625);
DISPLAY INVISIBLE (-2600 2625);
FORCEPROP 1 LAST PATH I65
J 0
(-2927 2750);
DISPLAY 0.872340 (-2927 2750);
PAINT GREEN (-2927 2750);
DISPLAY INVISIBLE (-2927 2750);
FORCEADD TAP..1
(-2925 2700);
FORCEPROP 3 LASTPIN (-2975 2700) SIG_NAME UPI_CPU0_CPU1_P0P0_DP<18>
J 0
(-2965 2710);
DISPLAY 0.659574 (-2965 2710);
PAINT MONO (-2965 2710);
DISPLAY INVISIBLE (-2965 2710);
FORCEPROP 1 LASTPIN (-2975 2700) BN 18
J 0
(-2987 2708);
DISPLAY 0.617021 (-2987 2708);
PAINT PINK (-2987 2708);
FORCEPROP 2 LAST CDS_LIB mstr_standard
J 0
(-2925 2700);
PAINT MONO (-2925 2700);
DISPLAY INVISIBLE (-2925 2700);
FORCEPROP 1 LAST BODY_TYPE PLUMBING
J 0
(-2925 2750);
DISPLAY 1.446809 (-2925 2750);
PAINT GREEN (-2925 2750);
DISPLAY INVISIBLE (-2925 2750);
FORCEPROP 1 LAST HDL_TAP TRUE
J 0
(-2600 2575);
DISPLAY 1.446809 (-2600 2575);
PAINT GREEN (-2600 2575);
DISPLAY INVISIBLE (-2600 2575);
FORCEPROP 1 LAST PATH I66
J 0
(-2927 2700);
DISPLAY 0.872340 (-2927 2700);
PAINT GREEN (-2927 2700);
DISPLAY INVISIBLE (-2927 2700);
FORCEADD TAP..1
(-2925 2800);
FORCEPROP 3 LASTPIN (-2975 2800) SIG_NAME UPI_CPU0_CPU1_P0P0_DP<16>
J 0
(-2965 2810);
DISPLAY 0.659574 (-2965 2810);
PAINT MONO (-2965 2810);
DISPLAY INVISIBLE (-2965 2810);
FORCEPROP 1 LASTPIN (-2975 2800) BN 16
J 0
(-2987 2808);
DISPLAY 0.617021 (-2987 2808);
PAINT PINK (-2987 2808);
FORCEPROP 2 LAST CDS_LIB mstr_standard
J 0
(-2925 2800);
PAINT MONO (-2925 2800);
DISPLAY INVISIBLE (-2925 2800);
FORCEPROP 1 LAST BODY_TYPE PLUMBING
J 0
(-2925 2850);
DISPLAY 1.446809 (-2925 2850);
PAINT GREEN (-2925 2850);
DISPLAY INVISIBLE (-2925 2850);
FORCEPROP 1 LAST HDL_TAP TRUE
J 0
(-2600 2675);
DISPLAY 1.446809 (-2600 2675);
PAINT GREEN (-2600 2675);
DISPLAY INVISIBLE (-2600 2675);
FORCEPROP 1 LAST PATH I67
J 0
(-2927 2800);
DISPLAY 0.872340 (-2927 2800);
PAINT GREEN (-2927 2800);
DISPLAY INVISIBLE (-2927 2800);
FORCEADD TAP..1
(-2925 2850);
FORCEPROP 3 LASTPIN (-2975 2850) SIG_NAME UPI_CPU0_CPU1_P0P0_DP<15>
J 0
(-2965 2860);
DISPLAY 0.659574 (-2965 2860);
PAINT MONO (-2965 2860);
DISPLAY INVISIBLE (-2965 2860);
FORCEPROP 1 LASTPIN (-2975 2850) BN 15
J 0
(-2987 2858);
DISPLAY 0.617021 (-2987 2858);
PAINT PINK (-2987 2858);
FORCEPROP 2 LAST CDS_LIB mstr_standard
J 0
(-2925 2850);
PAINT MONO (-2925 2850);
DISPLAY INVISIBLE (-2925 2850);
FORCEPROP 1 LAST BODY_TYPE PLUMBING
J 0
(-2925 2900);
DISPLAY 1.446809 (-2925 2900);
PAINT GREEN (-2925 2900);
DISPLAY INVISIBLE (-2925 2900);
FORCEPROP 1 LAST HDL_TAP TRUE
J 0
(-2600 2725);
DISPLAY 1.446809 (-2600 2725);
PAINT GREEN (-2600 2725);
DISPLAY INVISIBLE (-2600 2725);
FORCEPROP 1 LAST PATH I68
J 0
(-2927 2850);
DISPLAY 0.872340 (-2927 2850);
PAINT GREEN (-2927 2850);
DISPLAY INVISIBLE (-2927 2850);
FORCEADD TAP..1
(-2925 2900);
FORCEPROP 3 LASTPIN (-2975 2900) SIG_NAME UPI_CPU0_CPU1_P0P0_DP<14>
J 0
(-2965 2910);
DISPLAY 0.659574 (-2965 2910);
PAINT MONO (-2965 2910);
DISPLAY INVISIBLE (-2965 2910);
FORCEPROP 1 LASTPIN (-2975 2900) BN 14
J 0
(-2987 2908);
DISPLAY 0.617021 (-2987 2908);
PAINT PINK (-2987 2908);
FORCEPROP 2 LAST CDS_LIB mstr_standard
J 0
(-2925 2900);
PAINT MONO (-2925 2900);
DISPLAY INVISIBLE (-2925 2900);
FORCEPROP 1 LAST BODY_TYPE PLUMBING
J 0
(-2925 2950);
DISPLAY 1.446809 (-2925 2950);
PAINT GREEN (-2925 2950);
DISPLAY INVISIBLE (-2925 2950);
FORCEPROP 1 LAST HDL_TAP TRUE
J 0
(-2600 2775);
DISPLAY 1.446809 (-2600 2775);
PAINT GREEN (-2600 2775);
DISPLAY INVISIBLE (-2600 2775);
FORCEPROP 1 LAST PATH I69
J 0
(-2927 2900);
DISPLAY 0.872340 (-2927 2900);
PAINT GREEN (-2927 2900);
DISPLAY INVISIBLE (-2927 2900);
FORCEADD TAP..1
R 2
(-5250 1800);
FORCEPROP 3 LASTPIN (-5200 1800) SIG_NAME UPI_CPU1_CPU0_P0P0_DN<15>
J 0
(-5190 1810);
DISPLAY 0.659574 (-5190 1810);
PAINT MONO (-5190 1810);
DISPLAY INVISIBLE (-5190 1810);
FORCEPROP 1 LASTPIN (-5200 1800) BN 15
J 2
(-5188 1808);
DISPLAY 0.617021 (-5188 1808);
PAINT PINK (-5188 1808);
FORCEPROP 2 LAST CDS_LIB mstr_standard
J 0
(-5250 1800);
PAINT MONO (-5250 1800);
DISPLAY INVISIBLE (-5250 1800);
FORCEPROP 1 LAST BODY_TYPE PLUMBING
J 2
(-5250 1850);
DISPLAY 1.446809 (-5250 1850);
PAINT GREEN (-5250 1850);
DISPLAY INVISIBLE (-5250 1850);
FORCEPROP 1 LAST HDL_TAP TRUE
J 2
(-5575 1675);
DISPLAY 1.446809 (-5575 1675);
PAINT GREEN (-5575 1675);
DISPLAY INVISIBLE (-5575 1675);
FORCEPROP 1 LAST PATH I7
J 2
(-5248 1800);
DISPLAY 0.872340 (-5248 1800);
PAINT GREEN (-5248 1800);
DISPLAY INVISIBLE (-5248 1800);
FORCEADD TAP..1
(-2925 3000);
FORCEPROP 3 LASTPIN (-2975 3000) SIG_NAME UPI_CPU0_CPU1_P0P0_DP<12>
J 0
(-2965 3010);
DISPLAY 0.659574 (-2965 3010);
PAINT MONO (-2965 3010);
DISPLAY INVISIBLE (-2965 3010);
FORCEPROP 1 LASTPIN (-2975 3000) BN 12
J 0
(-2987 3008);
DISPLAY 0.617021 (-2987 3008);
PAINT PINK (-2987 3008);
FORCEPROP 2 LAST CDS_LIB mstr_standard
J 0
(-2925 3000);
PAINT MONO (-2925 3000);
DISPLAY INVISIBLE (-2925 3000);
FORCEPROP 1 LAST BODY_TYPE PLUMBING
J 0
(-2925 3050);
DISPLAY 1.446809 (-2925 3050);
PAINT GREEN (-2925 3050);
DISPLAY INVISIBLE (-2925 3050);
FORCEPROP 1 LAST HDL_TAP TRUE
J 0
(-2600 2875);
DISPLAY 1.446809 (-2600 2875);
PAINT GREEN (-2600 2875);
DISPLAY INVISIBLE (-2600 2875);
FORCEPROP 1 LAST PATH I70
J 0
(-2927 3000);
DISPLAY 0.872340 (-2927 3000);
PAINT GREEN (-2927 3000);
DISPLAY INVISIBLE (-2927 3000);
FORCEADD TAP..1
(-2925 2950);
FORCEPROP 3 LASTPIN (-2975 2950) SIG_NAME UPI_CPU0_CPU1_P0P0_DP<13>
J 0
(-2965 2960);
DISPLAY 0.659574 (-2965 2960);
PAINT MONO (-2965 2960);
DISPLAY INVISIBLE (-2965 2960);
FORCEPROP 1 LASTPIN (-2975 2950) BN 13
J 0
(-2987 2958);
DISPLAY 0.617021 (-2987 2958);
PAINT PINK (-2987 2958);
FORCEPROP 2 LAST CDS_LIB mstr_standard
J 0
(-2925 2950);
PAINT MONO (-2925 2950);
DISPLAY INVISIBLE (-2925 2950);
FORCEPROP 1 LAST BODY_TYPE PLUMBING
J 0
(-2925 3000);
DISPLAY 1.446809 (-2925 3000);
PAINT GREEN (-2925 3000);
DISPLAY INVISIBLE (-2925 3000);
FORCEPROP 1 LAST HDL_TAP TRUE
J 0
(-2600 2825);
DISPLAY 1.446809 (-2600 2825);
PAINT GREEN (-2600 2825);
DISPLAY INVISIBLE (-2600 2825);
FORCEPROP 1 LAST PATH I71
J 0
(-2927 2950);
DISPLAY 0.872340 (-2927 2950);
PAINT GREEN (-2927 2950);
DISPLAY INVISIBLE (-2927 2950);
FORCEADD TAP..1
(-2925 3050);
FORCEPROP 3 LASTPIN (-2975 3050) SIG_NAME UPI_CPU0_CPU1_P0P0_DP<11>
J 0
(-2965 3060);
DISPLAY 0.659574 (-2965 3060);
PAINT MONO (-2965 3060);
DISPLAY INVISIBLE (-2965 3060);
FORCEPROP 1 LASTPIN (-2975 3050) BN 11
J 0
(-2987 3058);
DISPLAY 0.617021 (-2987 3058);
PAINT PINK (-2987 3058);
FORCEPROP 2 LAST CDS_LIB mstr_standard
J 0
(-2925 3050);
PAINT MONO (-2925 3050);
DISPLAY INVISIBLE (-2925 3050);
FORCEPROP 1 LAST BODY_TYPE PLUMBING
J 0
(-2925 3100);
DISPLAY 1.446809 (-2925 3100);
PAINT GREEN (-2925 3100);
DISPLAY INVISIBLE (-2925 3100);
FORCEPROP 1 LAST HDL_TAP TRUE
J 0
(-2600 2925);
DISPLAY 1.446809 (-2600 2925);
PAINT GREEN (-2600 2925);
DISPLAY INVISIBLE (-2600 2925);
FORCEPROP 1 LAST PATH I72
J 0
(-2927 3050);
DISPLAY 0.872340 (-2927 3050);
PAINT GREEN (-2927 3050);
DISPLAY INVISIBLE (-2927 3050);
FORCEADD TAP..1
(-2925 3100);
FORCEPROP 3 LASTPIN (-2975 3100) SIG_NAME UPI_CPU0_CPU1_P0P0_DP<10>
J 0
(-2965 3110);
DISPLAY 0.659574 (-2965 3110);
PAINT MONO (-2965 3110);
DISPLAY INVISIBLE (-2965 3110);
FORCEPROP 1 LASTPIN (-2975 3100) BN 10
J 0
(-2987 3108);
DISPLAY 0.617021 (-2987 3108);
PAINT PINK (-2987 3108);
FORCEPROP 2 LAST CDS_LIB mstr_standard
J 0
(-2925 3100);
PAINT MONO (-2925 3100);
DISPLAY INVISIBLE (-2925 3100);
FORCEPROP 1 LAST BODY_TYPE PLUMBING
J 0
(-2925 3150);
DISPLAY 1.446809 (-2925 3150);
PAINT GREEN (-2925 3150);
DISPLAY INVISIBLE (-2925 3150);
FORCEPROP 1 LAST HDL_TAP TRUE
J 0
(-2600 2975);
DISPLAY 1.446809 (-2600 2975);
PAINT GREEN (-2600 2975);
DISPLAY INVISIBLE (-2600 2975);
FORCEPROP 1 LAST PATH I73
J 0
(-2927 3100);
DISPLAY 0.872340 (-2927 3100);
PAINT GREEN (-2927 3100);
DISPLAY INVISIBLE (-2927 3100);
FORCEADD TAP..1
(-2925 3150);
FORCEPROP 3 LASTPIN (-2975 3150) SIG_NAME UPI_CPU0_CPU1_P0P0_DP<9>
J 0
(-2965 3160);
DISPLAY 0.659574 (-2965 3160);
PAINT MONO (-2965 3160);
DISPLAY INVISIBLE (-2965 3160);
FORCEPROP 1 LASTPIN (-2975 3150) BN 9
J 0
(-2987 3158);
DISPLAY 0.617021 (-2987 3158);
PAINT PINK (-2987 3158);
FORCEPROP 2 LAST CDS_LIB mstr_standard
J 0
(-2925 3150);
PAINT MONO (-2925 3150);
DISPLAY INVISIBLE (-2925 3150);
FORCEPROP 1 LAST BODY_TYPE PLUMBING
J 0
(-2925 3200);
DISPLAY 1.446809 (-2925 3200);
PAINT GREEN (-2925 3200);
DISPLAY INVISIBLE (-2925 3200);
FORCEPROP 1 LAST HDL_TAP TRUE
J 0
(-2600 3025);
DISPLAY 1.446809 (-2600 3025);
PAINT GREEN (-2600 3025);
DISPLAY INVISIBLE (-2600 3025);
FORCEPROP 1 LAST PATH I74
J 0
(-2927 3150);
DISPLAY 0.872340 (-2927 3150);
PAINT GREEN (-2927 3150);
DISPLAY INVISIBLE (-2927 3150);
FORCEADD TAP..1
(-2925 3250);
FORCEPROP 3 LASTPIN (-2975 3250) SIG_NAME UPI_CPU0_CPU1_P0P0_DP<7>
J 0
(-2965 3260);
DISPLAY 0.659574 (-2965 3260);
PAINT MONO (-2965 3260);
DISPLAY INVISIBLE (-2965 3260);
FORCEPROP 1 LASTPIN (-2975 3250) BN 7
J 0
(-2987 3258);
DISPLAY 0.617021 (-2987 3258);
PAINT PINK (-2987 3258);
FORCEPROP 2 LAST CDS_LIB mstr_standard
J 0
(-2925 3250);
PAINT MONO (-2925 3250);
DISPLAY INVISIBLE (-2925 3250);
FORCEPROP 1 LAST BODY_TYPE PLUMBING
J 0
(-2925 3300);
DISPLAY 1.446809 (-2925 3300);
PAINT GREEN (-2925 3300);
DISPLAY INVISIBLE (-2925 3300);
FORCEPROP 1 LAST HDL_TAP TRUE
J 0
(-2600 3125);
DISPLAY 1.446809 (-2600 3125);
PAINT GREEN (-2600 3125);
DISPLAY INVISIBLE (-2600 3125);
FORCEPROP 1 LAST PATH I75
J 0
(-2927 3250);
DISPLAY 0.872340 (-2927 3250);
PAINT GREEN (-2927 3250);
DISPLAY INVISIBLE (-2927 3250);
FORCEADD TAP..1
(-2925 3300);
FORCEPROP 3 LASTPIN (-2975 3300) SIG_NAME UPI_CPU0_CPU1_P0P0_DP<6>
J 0
(-2965 3310);
DISPLAY 0.659574 (-2965 3310);
PAINT MONO (-2965 3310);
DISPLAY INVISIBLE (-2965 3310);
FORCEPROP 1 LASTPIN (-2975 3300) BN 6
J 0
(-2987 3308);
DISPLAY 0.617021 (-2987 3308);
PAINT PINK (-2987 3308);
FORCEPROP 2 LAST CDS_LIB mstr_standard
J 0
(-2925 3300);
PAINT MONO (-2925 3300);
DISPLAY INVISIBLE (-2925 3300);
FORCEPROP 1 LAST BODY_TYPE PLUMBING
J 0
(-2925 3350);
DISPLAY 1.446809 (-2925 3350);
PAINT GREEN (-2925 3350);
DISPLAY INVISIBLE (-2925 3350);
FORCEPROP 1 LAST HDL_TAP TRUE
J 0
(-2600 3175);
DISPLAY 1.446809 (-2600 3175);
PAINT GREEN (-2600 3175);
DISPLAY INVISIBLE (-2600 3175);
FORCEPROP 1 LAST PATH I76
J 0
(-2927 3300);
DISPLAY 0.872340 (-2927 3300);
PAINT GREEN (-2927 3300);
DISPLAY INVISIBLE (-2927 3300);
FORCEADD TAP..1
(-2925 3200);
FORCEPROP 3 LASTPIN (-2975 3200) SIG_NAME UPI_CPU0_CPU1_P0P0_DP<8>
J 0
(-2965 3210);
DISPLAY 0.659574 (-2965 3210);
PAINT MONO (-2965 3210);
DISPLAY INVISIBLE (-2965 3210);
FORCEPROP 1 LASTPIN (-2975 3200) BN 8
J 0
(-2987 3208);
DISPLAY 0.617021 (-2987 3208);
PAINT PINK (-2987 3208);
FORCEPROP 2 LAST CDS_LIB mstr_standard
J 0
(-2925 3200);
PAINT MONO (-2925 3200);
DISPLAY INVISIBLE (-2925 3200);
FORCEPROP 1 LAST BODY_TYPE PLUMBING
J 0
(-2925 3250);
DISPLAY 1.446809 (-2925 3250);
PAINT GREEN (-2925 3250);
DISPLAY INVISIBLE (-2925 3250);
FORCEPROP 1 LAST HDL_TAP TRUE
J 0
(-2600 3075);
DISPLAY 1.446809 (-2600 3075);
PAINT GREEN (-2600 3075);
DISPLAY INVISIBLE (-2600 3075);
FORCEPROP 1 LAST PATH I77
J 0
(-2927 3200);
DISPLAY 0.872340 (-2927 3200);
PAINT GREEN (-2927 3200);
DISPLAY INVISIBLE (-2927 3200);
FORCEADD TAP..1
(-2925 3350);
FORCEPROP 3 LASTPIN (-2975 3350) SIG_NAME UPI_CPU0_CPU1_P0P0_DP<5>
J 0
(-2965 3360);
DISPLAY 0.659574 (-2965 3360);
PAINT MONO (-2965 3360);
DISPLAY INVISIBLE (-2965 3360);
FORCEPROP 1 LASTPIN (-2975 3350) BN 5
J 0
(-2987 3358);
DISPLAY 0.617021 (-2987 3358);
PAINT PINK (-2987 3358);
FORCEPROP 2 LAST CDS_LIB mstr_standard
J 0
(-2925 3350);
PAINT MONO (-2925 3350);
DISPLAY INVISIBLE (-2925 3350);
FORCEPROP 1 LAST BODY_TYPE PLUMBING
J 0
(-2925 3400);
DISPLAY 1.446809 (-2925 3400);
PAINT GREEN (-2925 3400);
DISPLAY INVISIBLE (-2925 3400);
FORCEPROP 1 LAST HDL_TAP TRUE
J 0
(-2600 3225);
DISPLAY 1.446809 (-2600 3225);
PAINT GREEN (-2600 3225);
DISPLAY INVISIBLE (-2600 3225);
FORCEPROP 1 LAST PATH I78
J 0
(-2927 3350);
DISPLAY 0.872340 (-2927 3350);
PAINT GREEN (-2927 3350);
DISPLAY INVISIBLE (-2927 3350);
FORCEADD TAP..1
(-2925 3400);
FORCEPROP 3 LASTPIN (-2975 3400) SIG_NAME UPI_CPU0_CPU1_P0P0_DP<4>
J 0
(-2965 3410);
DISPLAY 0.659574 (-2965 3410);
PAINT MONO (-2965 3410);
DISPLAY INVISIBLE (-2965 3410);
FORCEPROP 1 LASTPIN (-2975 3400) BN 4
J 0
(-2987 3408);
DISPLAY 0.617021 (-2987 3408);
PAINT PINK (-2987 3408);
FORCEPROP 2 LAST CDS_LIB mstr_standard
J 0
(-2925 3400);
PAINT MONO (-2925 3400);
DISPLAY INVISIBLE (-2925 3400);
FORCEPROP 1 LAST BODY_TYPE PLUMBING
J 0
(-2925 3450);
DISPLAY 1.446809 (-2925 3450);
PAINT GREEN (-2925 3450);
DISPLAY INVISIBLE (-2925 3450);
FORCEPROP 1 LAST HDL_TAP TRUE
J 0
(-2600 3275);
DISPLAY 1.446809 (-2600 3275);
PAINT GREEN (-2600 3275);
DISPLAY INVISIBLE (-2600 3275);
FORCEPROP 1 LAST PATH I79
J 0
(-2927 3400);
DISPLAY 0.872340 (-2927 3400);
PAINT GREEN (-2927 3400);
DISPLAY INVISIBLE (-2927 3400);
FORCEADD TAP..1
R 2
(-5250 1850);
FORCEPROP 3 LASTPIN (-5200 1850) SIG_NAME UPI_CPU1_CPU0_P0P0_DN<14>
J 0
(-5190 1860);
DISPLAY 0.659574 (-5190 1860);
PAINT MONO (-5190 1860);
DISPLAY INVISIBLE (-5190 1860);
FORCEPROP 1 LASTPIN (-5200 1850) BN 14
J 2
(-5188 1858);
DISPLAY 0.617021 (-5188 1858);
PAINT PINK (-5188 1858);
FORCEPROP 2 LAST CDS_LIB mstr_standard
J 0
(-5250 1850);
PAINT MONO (-5250 1850);
DISPLAY INVISIBLE (-5250 1850);
FORCEPROP 1 LAST BODY_TYPE PLUMBING
J 2
(-5250 1900);
DISPLAY 1.446809 (-5250 1900);
PAINT GREEN (-5250 1900);
DISPLAY INVISIBLE (-5250 1900);
FORCEPROP 1 LAST HDL_TAP TRUE
J 2
(-5575 1725);
DISPLAY 1.446809 (-5575 1725);
PAINT GREEN (-5575 1725);
DISPLAY INVISIBLE (-5575 1725);
FORCEPROP 1 LAST PATH I8
J 2
(-5248 1850);
DISPLAY 0.872340 (-5248 1850);
PAINT GREEN (-5248 1850);
DISPLAY INVISIBLE (-5248 1850);
FORCEADD TAP..1
(-2925 3550);
FORCEPROP 3 LASTPIN (-2975 3550) SIG_NAME UPI_CPU0_CPU1_P0P0_DP<1>
J 0
(-2965 3560);
DISPLAY 0.659574 (-2965 3560);
PAINT MONO (-2965 3560);
DISPLAY INVISIBLE (-2965 3560);
FORCEPROP 1 LASTPIN (-2975 3550) BN 1
J 0
(-2987 3558);
DISPLAY 0.617021 (-2987 3558);
PAINT PINK (-2987 3558);
FORCEPROP 2 LAST CDS_LIB mstr_standard
J 0
(-2925 3550);
PAINT MONO (-2925 3550);
DISPLAY INVISIBLE (-2925 3550);
FORCEPROP 1 LAST BODY_TYPE PLUMBING
J 0
(-2925 3600);
DISPLAY 1.446809 (-2925 3600);
PAINT GREEN (-2925 3600);
DISPLAY INVISIBLE (-2925 3600);
FORCEPROP 1 LAST HDL_TAP TRUE
J 0
(-2600 3425);
DISPLAY 1.446809 (-2600 3425);
PAINT GREEN (-2600 3425);
DISPLAY INVISIBLE (-2600 3425);
FORCEPROP 1 LAST PATH I80
J 0
(-2927 3550);
DISPLAY 0.872340 (-2927 3550);
PAINT GREEN (-2927 3550);
DISPLAY INVISIBLE (-2927 3550);
FORCEADD TAP..1
(-2925 3500);
FORCEPROP 3 LASTPIN (-2975 3500) SIG_NAME UPI_CPU0_CPU1_P0P0_DP<2>
J 0
(-2965 3510);
DISPLAY 0.659574 (-2965 3510);
PAINT MONO (-2965 3510);
DISPLAY INVISIBLE (-2965 3510);
FORCEPROP 1 LASTPIN (-2975 3500) BN 2
J 0
(-2987 3508);
DISPLAY 0.617021 (-2987 3508);
PAINT PINK (-2987 3508);
FORCEPROP 2 LAST CDS_LIB mstr_standard
J 0
(-2925 3500);
PAINT MONO (-2925 3500);
DISPLAY INVISIBLE (-2925 3500);
FORCEPROP 1 LAST BODY_TYPE PLUMBING
J 0
(-2925 3550);
DISPLAY 1.446809 (-2925 3550);
PAINT GREEN (-2925 3550);
DISPLAY INVISIBLE (-2925 3550);
FORCEPROP 1 LAST HDL_TAP TRUE
J 0
(-2600 3375);
DISPLAY 1.446809 (-2600 3375);
PAINT GREEN (-2600 3375);
DISPLAY INVISIBLE (-2600 3375);
FORCEPROP 1 LAST PATH I81
J 0
(-2927 3500);
DISPLAY 0.872340 (-2927 3500);
PAINT GREEN (-2927 3500);
DISPLAY INVISIBLE (-2927 3500);
FORCEADD TAP..1
(-2925 3450);
FORCEPROP 3 LASTPIN (-2975 3450) SIG_NAME UPI_CPU0_CPU1_P0P0_DP<3>
J 0
(-2965 3460);
DISPLAY 0.659574 (-2965 3460);
PAINT MONO (-2965 3460);
DISPLAY INVISIBLE (-2965 3460);
FORCEPROP 1 LASTPIN (-2975 3450) BN 3
J 0
(-2987 3458);
DISPLAY 0.617021 (-2987 3458);
PAINT PINK (-2987 3458);
FORCEPROP 2 LAST CDS_LIB mstr_standard
J 0
(-2925 3450);
PAINT MONO (-2925 3450);
DISPLAY INVISIBLE (-2925 3450);
FORCEPROP 1 LAST BODY_TYPE PLUMBING
J 0
(-2925 3500);
DISPLAY 1.446809 (-2925 3500);
PAINT GREEN (-2925 3500);
DISPLAY INVISIBLE (-2925 3500);
FORCEPROP 1 LAST HDL_TAP TRUE
J 0
(-2600 3325);
DISPLAY 1.446809 (-2600 3325);
PAINT GREEN (-2600 3325);
DISPLAY INVISIBLE (-2600 3325);
FORCEPROP 1 LAST PATH I82
J 0
(-2927 3450);
DISPLAY 0.872340 (-2927 3450);
PAINT GREEN (-2927 3450);
DISPLAY INVISIBLE (-2927 3450);
FORCEADD TAP..1
(-2925 3600);
FORCEPROP 3 LASTPIN (-2975 3600) SIG_NAME UPI_CPU0_CPU1_P0P0_DP<0>
J 0
(-2965 3610);
DISPLAY 0.659574 (-2965 3610);
PAINT MONO (-2965 3610);
DISPLAY INVISIBLE (-2965 3610);
FORCEPROP 1 LASTPIN (-2975 3600) BN 0
J 0
(-2987 3608);
DISPLAY 0.617021 (-2987 3608);
PAINT PINK (-2987 3608);
FORCEPROP 2 LAST CDS_LIB mstr_standard
J 2
(-2925 3600);
PAINT MONO (-2925 3600);
DISPLAY INVISIBLE (-2925 3600);
FORCEPROP 1 LAST BODY_TYPE PLUMBING
J 0
(-2925 3650);
DISPLAY 1.446809 (-2925 3650);
PAINT GREEN (-2925 3650);
DISPLAY INVISIBLE (-2925 3650);
FORCEPROP 1 LAST HDL_TAP TRUE
J 0
(-2600 3475);
DISPLAY 1.446809 (-2600 3475);
PAINT GREEN (-2600 3475);
DISPLAY INVISIBLE (-2600 3475);
FORCEPROP 1 LAST PATH I83
J 0
(-2927 3600);
DISPLAY 0.872340 (-2927 3600);
PAINT GREEN (-2927 3600);
DISPLAY INVISIBLE (-2927 3600);
FORCEADD OFFPAGE..2
(-1725 2600);
FORCEPROP 2 LAST $XR0 67 
J 0
(-1536 2600);
DISPLAY 0.638298 (-1536 2600);
PAINT MONO (-1536 2600);
FORCEPROP 2 LAST CDS_LIB mstr_standard
J 0
(-1725 2600);
PAINT MONO (-1725 2600);
DISPLAY INVISIBLE (-1725 2600);
FORCEPROP 1 LAST OFFPAGE TRUE
J 0
(-1400 2475);
DISPLAY 1.170213 (-1400 2475);
PAINT GREEN (-1400 2475);
DISPLAY INVISIBLE (-1400 2475);
FORCEPROP 1 LAST COMMENT_BODY TRUE
J 0
(-1770 2505);
DISPLAY 1.170213 (-1770 2505);
PAINT GREEN (-1770 2505);
DISPLAY INVISIBLE (-1770 2505);
FORCEPROP 2 LAST PATH I84
J 0
(-1550 2675);
DISPLAY 1.021277 (-1550 2675);
PAINT ORANGE (-1550 2675);
DISPLAY INVISIBLE (-1550 2675);
FORCEADD OFFPAGE..2
(-1725 3650);
FORCEPROP 2 LAST $XR0 67 
J 0
(-1536 3650);
DISPLAY 0.638298 (-1536 3650);
PAINT MONO (-1536 3650);
FORCEPROP 2 LAST CDS_LIB mstr_standard
J 0
(-1725 3650);
PAINT MONO (-1725 3650);
DISPLAY INVISIBLE (-1725 3650);
FORCEPROP 1 LAST OFFPAGE TRUE
J 0
(-1400 3525);
DISPLAY 1.170213 (-1400 3525);
PAINT GREEN (-1400 3525);
DISPLAY INVISIBLE (-1400 3525);
FORCEPROP 1 LAST COMMENT_BODY TRUE
J 0
(-1770 3555);
DISPLAY 1.170213 (-1770 3555);
PAINT GREEN (-1770 3555);
DISPLAY INVISIBLE (-1770 3555);
FORCEPROP 2 LAST PATH I85
J 0
(-1550 3725);
DISPLAY 1.021277 (-1550 3725);
PAINT ORANGE (-1550 3725);
DISPLAY INVISIBLE (-1550 3725);
FORCEADD SKX_EXT_B..13
(-4075 2600);
FORCEPROP 1 LAST PART_NUMBER TBD
J 0
(-4825 1400);
DISPLAY 0.617021 (-4825 1400);
PAINT BLUE (-4825 1400);
FORCEPROP 1 LAST MATERIAL IC
J 0
(-4825 3800);
DISPLAY 0.617021 (-4825 3800);
PAINT SKYBLUE (-4825 3800);
FORCEPROP 2 LASTPIN (-3275 3600) $PN BH3
J 0
(-3265 3610);
DISPLAY 0.617021 (-3265 3610);
PAINT ORANGE (-3265 3610);
FORCEPROP 2 LASTPIN (-3275 3550) $PN BD3
J 0
(-3265 3560);
DISPLAY 0.617021 (-3265 3560);
PAINT ORANGE (-3265 3560);
FORCEPROP 2 LASTPIN (-3275 3500) $PN BC2
J 0
(-3265 3510);
DISPLAY 0.617021 (-3265 3510);
PAINT ORANGE (-3265 3510);
FORCEPROP 2 LASTPIN (-3275 3450) $PN AY3
J 0
(-3265 3460);
DISPLAY 0.617021 (-3265 3460);
PAINT ORANGE (-3265 3460);
FORCEPROP 2 LASTPIN (-3275 3400) $PN AW4
J 0
(-3265 3410);
DISPLAY 0.617021 (-3265 3410);
PAINT ORANGE (-3265 3410);
FORCEPROP 2 LASTPIN (-3275 3350) $PN AR4
J 0
(-3265 3360);
DISPLAY 0.617021 (-3265 3360);
PAINT ORANGE (-3265 3360);
FORCEPROP 2 LASTPIN (-3275 3300) $PN AR2
J 0
(-3265 3310);
DISPLAY 0.617021 (-3265 3310);
PAINT ORANGE (-3265 3310);
FORCEPROP 2 LASTPIN (-3275 3250) $PN AP1
J 0
(-3265 3260);
DISPLAY 0.617021 (-3265 3260);
PAINT ORANGE (-3265 3260);
FORCEPROP 2 LASTPIN (-3275 3200) $PN AP3
J 0
(-3265 3210);
DISPLAY 0.617021 (-3265 3210);
PAINT ORANGE (-3265 3210);
FORCEPROP 2 LASTPIN (-3275 3150) $PN AK3
J 0
(-3265 3160);
DISPLAY 0.617021 (-3265 3160);
PAINT ORANGE (-3265 3160);
FORCEPROP 2 LASTPIN (-3275 3100) $PN AK1
J 0
(-3265 3110);
DISPLAY 0.617021 (-3265 3110);
PAINT ORANGE (-3265 3110);
FORCEPROP 2 LASTPIN (-3275 3050) $PN AJ2
J 0
(-3265 3060);
DISPLAY 0.617021 (-3265 3060);
PAINT ORANGE (-3265 3060);
FORCEPROP 2 LASTPIN (-3275 3000) $PN AG2
J 0
(-3265 3010);
DISPLAY 0.617021 (-3265 3010);
PAINT ORANGE (-3265 3010);
FORCEPROP 2 LASTPIN (-3275 2950) $PN AF3
J 0
(-3265 2960);
DISPLAY 0.617021 (-3265 2960);
PAINT ORANGE (-3265 2960);
FORCEPROP 2 LASTPIN (-3275 2900) $PN AD1
J 0
(-3265 2910);
DISPLAY 0.617021 (-3265 2910);
PAINT ORANGE (-3265 2910);
FORCEPROP 2 LASTPIN (-3275 2850) $PN AA2
J 0
(-3265 2860);
DISPLAY 0.617021 (-3265 2860);
PAINT ORANGE (-3265 2860);
FORCEPROP 2 LASTPIN (-3275 2800) $PN W2
J 0
(-3265 2810);
DISPLAY 0.617021 (-3265 2810);
PAINT ORANGE (-3265 2810);
FORCEPROP 2 LASTPIN (-3275 2750) $PN Y3
J 0
(-3265 2760);
DISPLAY 0.617021 (-3265 2760);
PAINT ORANGE (-3265 2760);
FORCEPROP 2 LASTPIN (-3275 2700) $PN T1
J 0
(-3265 2710);
DISPLAY 0.617021 (-3265 2710);
PAINT ORANGE (-3265 2710);
FORCEPROP 2 LASTPIN (-3275 2650) $PN M1
J 0
(-3265 2660);
DISPLAY 0.617021 (-3265 2660);
PAINT ORANGE (-3265 2660);
FORCEPROP 2 LASTPIN (-3275 2550) $PN BG4
J 0
(-3265 2560);
DISPLAY 0.617021 (-3265 2560);
PAINT ORANGE (-3265 2560);
FORCEPROP 2 LASTPIN (-3275 2500) $PN BF3
J 0
(-3265 2510);
DISPLAY 0.617021 (-3265 2510);
PAINT ORANGE (-3265 2510);
FORCEPROP 2 LASTPIN (-3275 2450) $PN BB3
J 0
(-3265 2460);
DISPLAY 0.617021 (-3265 2460);
PAINT ORANGE (-3265 2460);
FORCEPROP 2 LASTPIN (-3275 2400) $PN BA4
J 0
(-3265 2410);
DISPLAY 0.617021 (-3265 2410);
PAINT ORANGE (-3265 2410);
FORCEPROP 2 LASTPIN (-3275 2350) $PN AV5
J 0
(-3265 2360);
DISPLAY 0.617021 (-3265 2360);
PAINT ORANGE (-3265 2360);
FORCEPROP 2 LASTPIN (-3275 2300) $PN AU4
J 0
(-3265 2310);
DISPLAY 0.617021 (-3265 2310);
PAINT ORANGE (-3265 2310);
FORCEPROP 2 LASTPIN (-3275 2250) $PN AT3
J 0
(-3265 2260);
DISPLAY 0.617021 (-3265 2260);
PAINT ORANGE (-3265 2260);
FORCEPROP 2 LASTPIN (-3275 2200) $PN AT1
J 0
(-3265 2210);
DISPLAY 0.617021 (-3265 2210);
PAINT ORANGE (-3265 2210);
FORCEPROP 2 LASTPIN (-3275 2150) $PN AN4
J 0
(-3265 2160);
DISPLAY 0.617021 (-3265 2160);
PAINT ORANGE (-3265 2160);
FORCEPROP 2 LASTPIN (-3275 2100) $PN AM3
J 0
(-3265 2110);
DISPLAY 0.617021 (-3265 2110);
PAINT ORANGE (-3265 2110);
FORCEPROP 2 LASTPIN (-3275 2050) $PN AL2
J 0
(-3265 2060);
DISPLAY 0.617021 (-3265 2060);
PAINT ORANGE (-3265 2060);
FORCEPROP 2 LASTPIN (-3275 2000) $PN AH3
J 0
(-3265 2010);
DISPLAY 0.617021 (-3265 2010);
PAINT ORANGE (-3265 2010);
FORCEPROP 2 LASTPIN (-3275 1950) $PN AE2
J 0
(-3265 1960);
DISPLAY 0.617021 (-3265 1960);
PAINT ORANGE (-3265 1960);
FORCEPROP 2 LASTPIN (-3275 1900) $PN AG4
J 0
(-3265 1910);
DISPLAY 0.617021 (-3265 1910);
PAINT ORANGE (-3265 1910);
FORCEPROP 2 LASTPIN (-3275 1850) $PN AC2
J 0
(-3265 1860);
DISPLAY 0.617021 (-3265 1860);
PAINT ORANGE (-3265 1860);
FORCEPROP 2 LASTPIN (-3275 1800) $PN AB3
J 0
(-3265 1810);
DISPLAY 0.617021 (-3265 1810);
PAINT ORANGE (-3265 1810);
FORCEPROP 2 LASTPIN (-3275 1750) $PN Y1
J 0
(-3265 1760);
DISPLAY 0.617021 (-3265 1760);
PAINT ORANGE (-3265 1760);
FORCEPROP 2 LASTPIN (-3275 1700) $PN V3
J 0
(-3265 1710);
DISPLAY 0.617021 (-3265 1710);
PAINT ORANGE (-3265 1710);
FORCEPROP 2 LASTPIN (-3275 1650) $PN P1
J 0
(-3265 1660);
DISPLAY 0.617021 (-3265 1660);
PAINT ORANGE (-3265 1660);
FORCEPROP 2 LASTPIN (-3275 1600) $PN N2
J 0
(-3265 1610);
DISPLAY 0.617021 (-3265 1610);
PAINT ORANGE (-3265 1610);
FORCEPROP 2 LASTPIN (-4875 3600) $PN BA10
J 2
(-4885 3610);
DISPLAY 0.617021 (-4885 3610);
PAINT ORANGE (-4885 3610);
FORCEPROP 2 LASTPIN (-4875 3550) $PN BC10
J 2
(-4885 3560);
DISPLAY 0.617021 (-4885 3560);
PAINT ORANGE (-4885 3560);
FORCEPROP 2 LASTPIN (-4875 3500) $PN BB9
J 2
(-4885 3510);
DISPLAY 0.617021 (-4885 3510);
PAINT ORANGE (-4885 3510);
FORCEPROP 2 LASTPIN (-4875 3450) $PN AV9
J 2
(-4885 3460);
DISPLAY 0.617021 (-4885 3460);
PAINT ORANGE (-4885 3460);
FORCEPROP 2 LASTPIN (-4875 3400) $PN BF7
J 2
(-4885 3410);
DISPLAY 0.617021 (-4885 3410);
PAINT ORANGE (-4885 3410);
FORCEPROP 2 LASTPIN (-4875 3350) $PN BB7
J 2
(-4885 3360);
DISPLAY 0.617021 (-4885 3360);
PAINT ORANGE (-4885 3360);
FORCEPROP 2 LASTPIN (-4875 3300) $PN AY7
J 2
(-4885 3310);
DISPLAY 0.617021 (-4885 3310);
PAINT ORANGE (-4885 3310);
FORCEPROP 2 LASTPIN (-4875 3250) $PN AT9
J 2
(-4885 3260);
DISPLAY 0.617021 (-4885 3260);
PAINT ORANGE (-4885 3260);
FORCEPROP 2 LASTPIN (-4875 3200) $PN AU8
J 2
(-4885 3210);
DISPLAY 0.617021 (-4885 3210);
PAINT ORANGE (-4885 3210);
FORCEPROP 2 LASTPIN (-4875 3150) $PN AN8
J 2
(-4885 3160);
DISPLAY 0.617021 (-4885 3160);
PAINT ORANGE (-4885 3160);
FORCEPROP 2 LASTPIN (-4875 3100) $PN AL8
J 2
(-4885 3110);
DISPLAY 0.617021 (-4885 3110);
PAINT ORANGE (-4885 3110);
FORCEPROP 2 LASTPIN (-4875 3050) $PN AM7
J 2
(-4885 3060);
DISPLAY 0.617021 (-4885 3060);
PAINT ORANGE (-4885 3060);
FORCEPROP 2 LASTPIN (-4875 3000) $PN AK5
J 2
(-4885 3010);
DISPLAY 0.617021 (-4885 3010);
PAINT ORANGE (-4885 3010);
FORCEPROP 2 LASTPIN (-4875 2950) $PN AH7
J 2
(-4885 2960);
DISPLAY 0.617021 (-4885 2960);
PAINT ORANGE (-4885 2960);
FORCEPROP 2 LASTPIN (-4875 2900) $PN AF7
J 2
(-4885 2910);
DISPLAY 0.617021 (-4885 2910);
PAINT ORANGE (-4885 2910);
FORCEPROP 2 LASTPIN (-4875 2850) $PN AG6
J 2
(-4885 2860);
DISPLAY 0.617021 (-4885 2860);
PAINT ORANGE (-4885 2860);
FORCEPROP 2 LASTPIN (-4875 2800) $PN AC6
J 2
(-4885 2810);
DISPLAY 0.617021 (-4885 2810);
PAINT ORANGE (-4885 2810);
FORCEPROP 2 LASTPIN (-4875 2750) $PN AA6
J 2
(-4885 2760);
DISPLAY 0.617021 (-4885 2760);
PAINT ORANGE (-4885 2760);
FORCEPROP 2 LASTPIN (-4875 2700) $PN AC8
J 2
(-4885 2710);
DISPLAY 0.617021 (-4885 2710);
PAINT ORANGE (-4885 2710);
FORCEPROP 2 LASTPIN (-4875 2650) $PN AB9
J 2
(-4885 2660);
DISPLAY 0.617021 (-4885 2660);
PAINT ORANGE (-4885 2660);
FORCEPROP 2 LASTPIN (-4875 2550) $PN BB11
J 2
(-4885 2560);
DISPLAY 0.617021 (-4885 2560);
PAINT ORANGE (-4885 2560);
FORCEPROP 2 LASTPIN (-4875 2500) $PN BD9
J 2
(-4885 2510);
DISPLAY 0.617021 (-4885 2510);
PAINT ORANGE (-4885 2510);
FORCEPROP 2 LASTPIN (-4875 2450) $PN AY9
J 2
(-4885 2460);
DISPLAY 0.617021 (-4885 2460);
PAINT ORANGE (-4885 2460);
FORCEPROP 2 LASTPIN (-4875 2400) $PN AW8
J 2
(-4885 2410);
DISPLAY 0.617021 (-4885 2410);
PAINT ORANGE (-4885 2410);
FORCEPROP 2 LASTPIN (-4875 2350) $PN BD7
J 2
(-4885 2360);
DISPLAY 0.617021 (-4885 2360);
PAINT ORANGE (-4885 2360);
FORCEPROP 2 LASTPIN (-4875 2300) $PN BC6
J 2
(-4885 2310);
DISPLAY 0.617021 (-4885 2310);
PAINT ORANGE (-4885 2310);
FORCEPROP 2 LASTPIN (-4875 2250) $PN BA8
J 2
(-4885 2260);
DISPLAY 0.617021 (-4885 2260);
PAINT ORANGE (-4885 2260);
FORCEPROP 2 LASTPIN (-4875 2200) $PN AU10
J 2
(-4885 2210);
DISPLAY 0.617021 (-4885 2210);
PAINT ORANGE (-4885 2210);
FORCEPROP 2 LASTPIN (-4875 2150) $PN AR8
J 2
(-4885 2160);
DISPLAY 0.617021 (-4885 2160);
PAINT ORANGE (-4885 2160);
FORCEPROP 2 LASTPIN (-4875 2100) $PN AP7
J 2
(-4885 2110);
DISPLAY 0.617021 (-4885 2110);
PAINT ORANGE (-4885 2110);
FORCEPROP 2 LASTPIN (-4875 2050) $PN AM9
J 2
(-4885 2060);
DISPLAY 0.617021 (-4885 2060);
PAINT ORANGE (-4885 2060);
FORCEPROP 2 LASTPIN (-4875 2000) $PN AK7
J 2
(-4885 2010);
DISPLAY 0.617021 (-4885 2010);
PAINT ORANGE (-4885 2010);
FORCEPROP 2 LASTPIN (-4875 1950) $PN AL6
J 2
(-4885 1960);
DISPLAY 0.617021 (-4885 1960);
PAINT ORANGE (-4885 1960);
FORCEPROP 2 LASTPIN (-4875 1900) $PN AJ6
J 2
(-4885 1910);
DISPLAY 0.617021 (-4885 1910);
PAINT ORANGE (-4885 1910);
FORCEPROP 2 LASTPIN (-4875 1850) $PN AG8
J 2
(-4885 1860);
DISPLAY 0.617021 (-4885 1860);
PAINT ORANGE (-4885 1860);
FORCEPROP 2 LASTPIN (-4875 1800) $PN AE6
J 2
(-4885 1810);
DISPLAY 0.617021 (-4885 1810);
PAINT ORANGE (-4885 1810);
FORCEPROP 2 LASTPIN (-4875 1750) $PN AD5
J 2
(-4885 1760);
DISPLAY 0.617021 (-4885 1760);
PAINT ORANGE (-4885 1760);
FORCEPROP 2 LASTPIN (-4875 1700) $PN AB7
J 2
(-4885 1710);
DISPLAY 0.617021 (-4885 1710);
PAINT ORANGE (-4885 1710);
FORCEPROP 2 LASTPIN (-4875 1650) $PN AA8
J 2
(-4885 1660);
DISPLAY 0.617021 (-4885 1660);
PAINT ORANGE (-4885 1660);
FORCEPROP 2 LASTPIN (-4875 1600) $PN AC10
J 2
(-4885 1610);
DISPLAY 0.617021 (-4885 1610);
PAINT ORANGE (-4885 1610);
FORCEPROP 1 LAST LOCATION U5D1
J 0
(-4825 3850);
DISPLAY 0.617021 (-4825 3850);
PAINT AQUA (-4825 3850);
FORCEPROP 1 LAST PACK_TYPE BGA1
J 0
(-4825 3900);
PAINT SKYBLUE (-4825 3900);
DISPLAY INVISIBLE (-4825 3900);
FORCEPROP 2 LAST CDS_LIB chpset_lib
J 0
(-4075 2600);
PAINT ORANGE (-4075 2600);
DISPLAY INVISIBLE (-4075 2600);
FORCEPROP 2 LAST SEC_TYPE BGA1
J 0
(-4825 3900);
DISPLAY 1.021277 (-4825 3900);
PAINT ORANGE (-4825 3900);
DISPLAY INVISIBLE (-4825 3900);
FORCEPROP 2 LAST SEC 13
J 0
(-4825 3900);
DISPLAY 0.680851 (-4825 3900);
PAINT MONO (-4825 3900);
DISPLAY INVISIBLE (-4825 3900);
FORCEPROP 2 LAST CDS_LOCATION U5D1
J 0
(-4825 3850);
DISPLAY 0.617021 (-4825 3850);
PAINT AQUA (-4825 3850);
DISPLAY INVISIBLE (-4825 3850);
FORCEPROP 1 LAST PATH I86
J 0
(-4075 3800);
PAINT GREEN (-4075 3800);
DISPLAY INVISIBLE (-4075 3800);
FORCEPROP 0 LAST ROOM CPU0
J 0
(-4825 3950);
DISPLAY 1.021277 (-4825 3950);
PAINT ORANGE (-4825 3950);
DISPLAY INVISIBLE (-4825 3950);
FORCEADD TAP..1
R 2
(-5250 1950);
FORCEPROP 3 LASTPIN (-5200 1950) SIG_NAME UPI_CPU1_CPU0_P0P0_DN<12>
J 0
(-5190 1960);
DISPLAY 0.659574 (-5190 1960);
PAINT MONO (-5190 1960);
DISPLAY INVISIBLE (-5190 1960);
FORCEPROP 1 LASTPIN (-5200 1950) BN 12
J 2
(-5188 1958);
DISPLAY 0.617021 (-5188 1958);
PAINT PINK (-5188 1958);
FORCEPROP 2 LAST CDS_LIB mstr_standard
J 0
(-5250 1950);
PAINT MONO (-5250 1950);
DISPLAY INVISIBLE (-5250 1950);
FORCEPROP 1 LAST BODY_TYPE PLUMBING
J 2
(-5250 2000);
DISPLAY 1.446809 (-5250 2000);
PAINT GREEN (-5250 2000);
DISPLAY INVISIBLE (-5250 2000);
FORCEPROP 1 LAST HDL_TAP TRUE
J 2
(-5575 1825);
DISPLAY 1.446809 (-5575 1825);
PAINT GREEN (-5575 1825);
DISPLAY INVISIBLE (-5575 1825);
FORCEPROP 1 LAST PATH I9
J 2
(-5248 1950);
DISPLAY 0.872340 (-5248 1950);
PAINT GREEN (-5248 1950);
DISPLAY INVISIBLE (-5248 1950);
FORCEADD PRELIM..10
(-4065 2590);
PAINT GRAY (-4065 2590);
FORCEPROP 2 LAST CDS_LIB mstr_misc
J 0
(-4065 2590);
PAINT ORANGE (-4065 2590);
DISPLAY INVISIBLE (-4065 2590);
FORCEPROP 1 LAST COMMENT_BODY TRUE
J 0
(-4065 2590);
PAINT ORANGE (-4065 2590);
DISPLAY INVISIBLE (-4065 2590);
FORCEADD INTEL_CORP_BPAGE..1
(0 0);
FORCEPROP 1 LAST CDS_CON_LAST_MODIFIED Fri Jun 16 17:48:13 2017
J 0
(-1425 325);
DISPLAY 1.340426 (-1425 325);
PAINT GREEN (-1425 325);
DISPLAY INVISIBLE (-1425 325);
FORCEPROP 1 LAST CUSTOM_TXT_CDS <CURRENT_DESIGN_SHEET> OF <TOTAL_DESIGN_SHEETS>
J 0
(-500 25);
PAINT ORANGE (-500 25);
FORCEPROP 1 LAST CUSTOM_TXT_CDS <CON_LAST_MODIFIED>
J 0
(-4000 100);
PAINT ORANGE (-4000 100);
FORCEPROP 2 LAST CUSTOM_TXT_CDS <XR_PAGE_TITLE>
J 0
(-7890 5250);
DISPLAY 0.638298 (-7890 5250);
PAINT PINK (-7890 5250);
DISPLAY INVISIBLE (-7890 5250);
FORCEPROP 1 LAST SCH_TITLE SKYLAKE - SKT0 - 13 OF 21
J 0
(-7950 50);
DISPLAY 1.212766 (-7950 50);
PAINT GREEN (-7950 50);
FORCEPROP 2 LAST PAGE_BORDER TRUE
J 0
(-7890 5250);
DISPLAY 0.851064 (-7890 5250);
PAINT PINK (-7890 5250);
DISPLAY INVISIBLE (-7890 5250);
FORCEPROP 2 LAST CDS_LIB mstr_symbols
J 0
(0 0);
PAINT ORANGE (0 0);
DISPLAY INVISIBLE (0 0);
FORCEPROP 1 LAST COMMENT_BODY TRUE
J 0
(12 12);
DISPLAY 0.638298 (12 12);
PAINT GREEN (12 12);
DISPLAY INVISIBLE (12 12);
FORCEPROP 2 LAST CDS_XR_PAGE_TITLE CR-33 : @BASEBOARD_FAB2_LIB.BASEBOARD_FAB2(SCH_1):PAGE33
J 0
(-7890 5250);
DISPLAY 0.638298 (-7890 5250);
PAINT PINK (-7890 5250);
DISPLAY INVISIBLE (-7890 5250);
FORCEADD DESIGN_NOTE..1
(-4675 1275);
FORCEPROP 0 LAST L1 CPU SYMBOLS 1-30 ARE PRELIMINARY AND SUBJECT TO CHANGE
J 0
(-4875 1150);
DISPLAY 1.021277 (-4875 1150);
PAINT ORANGE (-4875 1150);
FORCEPROP 2 LAST CDS_LIB mstr_symbols
J 0
(-4675 1275);
PAINT ORANGE (-4675 1275);
DISPLAY INVISIBLE (-4675 1275);
FORCEPROP 1 LAST COMMENT_BODY TRUE
J 0
(-4650 1375);
DISPLAY 0.978723 (-4650 1375);
PAINT ORANGE (-4650 1375);
DISPLAY INVISIBLE (-4650 1375);
WIRE 17 -1 (-2875 1675)(-2875 1625);
WIRE 17 -1 (-2875 1725)(-2875 1675);
WIRE 17 -1 (-2875 1775)(-2875 1725);
WIRE 17 -1 (-2875 1825)(-2875 1775);
WIRE 17 -1 (-2875 1875)(-2875 1825);
WIRE 17 -1 (-2875 1925)(-2875 1875);
WIRE 17 -1 (-2875 1975)(-2875 1925);
WIRE 17 -1 (-2875 2025)(-2875 1975);
WIRE 17 -1 (-2875 2075)(-2875 2025);
WIRE 17 -1 (-2875 2125)(-2875 2075);
WIRE 17 -1 (-2875 2175)(-2875 2125);
WIRE 17 -1 (-2875 2225)(-2875 2175);
WIRE 17 -1 (-2875 2275)(-2875 2225);
WIRE 17 -1 (-2875 2325)(-2875 2275);
WIRE 17 -1 (-2875 2375)(-2875 2325);
WIRE 17 -1 (-2875 2425)(-2875 2375);
WIRE 17 -1 (-2875 2475)(-2875 2425);
WIRE 17 -1 (-2875 2525)(-2875 2475);
WIRE 17 -1 (-2875 2575)(-2875 2525);
WIRE 17 -1 (-2875 2600)(-1775 2600);
FORCEPROP 2 LAST SIG_NAME UPI_CPU0_CPU1_P0P0_DN<19..0>
J 0
(-2785 2610);
DISPLAY 0.617021 (-2785 2610);
PAINT ORANGE (-2785 2610);
WIRE 17 -1 (-2875 2600)(-2875 2575);
WIRE 17 -1 (-2875 2725)(-2875 2675);
WIRE 17 -1 (-2875 2775)(-2875 2725);
WIRE 17 -1 (-2875 2825)(-2875 2775);
WIRE 17 -1 (-2875 2875)(-2875 2825);
WIRE 17 -1 (-2875 2925)(-2875 2875);
WIRE 17 -1 (-2875 2975)(-2875 2925);
WIRE 17 -1 (-2875 3025)(-2875 2975);
WIRE 17 -1 (-2875 3075)(-2875 3025);
WIRE 17 -1 (-2875 3125)(-2875 3075);
WIRE 17 -1 (-2875 3175)(-2875 3125);
WIRE 17 -1 (-2875 3225)(-2875 3175);
WIRE 17 -1 (-2875 3275)(-2875 3225);
WIRE 17 -1 (-2875 3325)(-2875 3275);
WIRE 17 -1 (-2875 3375)(-2875 3325);
WIRE 17 -1 (-2875 3425)(-2875 3375);
WIRE 17 -1 (-2875 3475)(-2875 3425);
WIRE 17 -1 (-2875 3525)(-2875 3475);
WIRE 17 -1 (-2875 3575)(-2875 3525);
WIRE 17 -1 (-2875 3625)(-2875 3575);
WIRE 17 -1 (-2875 3650)(-1775 3650);
FORCEPROP 2 LAST SIG_NAME UPI_CPU0_CPU1_P0P0_DP<19..0>
J 0
(-2785 3660);
DISPLAY 0.617021 (-2785 3660);
PAINT ORANGE (-2785 3660);
WIRE 17 -1 (-2875 3650)(-2875 3625);
WIRE 17 -1 (-5300 1625)(-5300 1675);
WIRE 17 -1 (-5300 1675)(-5300 1725);
WIRE 17 -1 (-5300 1775)(-5300 1725);
WIRE 17 -1 (-5300 1825)(-5300 1775);
WIRE 17 -1 (-5300 1875)(-5300 1825);
WIRE 17 -1 (-5300 1925)(-5300 1875);
WIRE 17 -1 (-5300 1975)(-5300 1925);
WIRE 17 -1 (-5300 2025)(-5300 1975);
WIRE 17 -1 (-5300 2075)(-5300 2025);
WIRE 17 -1 (-5300 2125)(-5300 2075);
WIRE 17 -1 (-5300 2175)(-5300 2125);
WIRE 17 -1 (-5300 2225)(-5300 2175);
WIRE 17 -1 (-5300 2275)(-5300 2225);
WIRE 17 -1 (-5300 2325)(-5300 2275);
WIRE 17 -1 (-5300 2375)(-5300 2325);
WIRE 17 -1 (-5300 2425)(-5300 2375);
WIRE 17 -1 (-5300 2475)(-5300 2425);
WIRE 17 -1 (-6400 2600)(-5300 2600);
FORCEPROP 2 LAST SIG_NAME UPI_CPU1_CPU0_P0P0_DN<19..0>
J 0
(-6335 2610);
DISPLAY 0.617021 (-6335 2610);
PAINT ORANGE (-6335 2610);
WIRE 17 -1 (-5300 2575)(-5300 2600);
WIRE 17 -1 (-5300 2475)(-5300 2525);
WIRE 17 -1 (-5300 2525)(-5300 2575);
WIRE 17 -1 (-5300 2675)(-5300 2725);
WIRE 17 -1 (-5300 2725)(-5300 2775);
WIRE 17 -1 (-5300 2825)(-5300 2775);
WIRE 17 -1 (-5300 2875)(-5300 2825);
WIRE 17 -1 (-5300 2925)(-5300 2875);
WIRE 17 -1 (-5300 2975)(-5300 2925);
WIRE 17 -1 (-5300 3025)(-5300 2975);
WIRE 17 -1 (-5300 3075)(-5300 3025);
WIRE 17 -1 (-5300 3125)(-5300 3075);
WIRE 17 -1 (-5300 3175)(-5300 3125);
WIRE 17 -1 (-5300 3225)(-5300 3175);
WIRE 17 -1 (-5300 3275)(-5300 3225);
WIRE 17 -1 (-5300 3325)(-5300 3275);
WIRE 17 -1 (-5300 3375)(-5300 3325);
WIRE 17 -1 (-5300 3425)(-5300 3375);
WIRE 17 -1 (-5300 3475)(-5300 3425);
WIRE 17 -1 (-5300 3525)(-5300 3475);
WIRE 17 -1 (-6400 3650)(-5300 3650);
FORCEPROP 2 LAST SIG_NAME UPI_CPU1_CPU0_P0P0_DP<19..0>
J 0
(-6310 3660);
DISPLAY 0.617021 (-6310 3660);
PAINT ORANGE (-6310 3660);
WIRE 17 -1 (-5300 3650)(-5300 3625);
WIRE 17 -1 (-5300 3525)(-5300 3575);
WIRE 17 -1 (-5300 3575)(-5300 3625);
WIRE 16 -1 (-2975 3250)(-3275 3250);
WIRE 16 -1 (-5200 2900)(-4875 2900);
WIRE 16 -1 (-5200 3000)(-4875 3000);
WIRE 16 -1 (-5200 3150)(-4875 3150);
WIRE 16 -1 (-5200 3100)(-4875 3100);
WIRE 16 -1 (-5200 2950)(-4875 2950);
WIRE 16 -1 (-5200 1600)(-4875 1600);
WIRE 16 -1 (-5200 1650)(-4875 1650);
WIRE 16 -1 (-5200 1700)(-4875 1700);
WIRE 16 -1 (-5200 1750)(-4875 1750);
WIRE 16 -1 (-5200 1800)(-4875 1800);
WIRE 16 -1 (-5200 1850)(-4875 1850);
WIRE 16 -1 (-5200 1900)(-4875 1900);
WIRE 16 -1 (-5200 1950)(-4875 1950);
WIRE 16 -1 (-5200 2000)(-4875 2000);
WIRE 16 -1 (-5200 2650)(-4875 2650);
WIRE 16 -1 (-5200 2700)(-4875 2700);
WIRE 16 -1 (-5200 2750)(-4875 2750);
WIRE 16 -1 (-5200 2800)(-4875 2800);
WIRE 16 -1 (-5200 2850)(-4875 2850);
WIRE 16 -1 (-5200 3050)(-4875 3050);
WIRE 16 -1 (-5200 3200)(-4875 3200);
WIRE 16 -1 (-5200 3250)(-4875 3250);
WIRE 16 -1 (-5200 3300)(-4875 3300);
WIRE 16 -1 (-5200 3350)(-4875 3350);
WIRE 16 -1 (-5200 3400)(-4875 3400);
WIRE 16 -1 (-5200 3450)(-4875 3450);
WIRE 16 -1 (-5200 3500)(-4875 3500);
WIRE 16 -1 (-5200 3550)(-4875 3550);
WIRE 16 -1 (-5200 3600)(-4875 3600);
WIRE 16 -1 (-5200 2050)(-4875 2050);
WIRE 16 -1 (-5200 2100)(-4875 2100);
WIRE 16 -1 (-5200 2150)(-4875 2150);
WIRE 16 -1 (-5200 2200)(-4875 2200);
WIRE 16 -1 (-5200 2250)(-4875 2250);
WIRE 16 -1 (-5200 2300)(-4875 2300);
WIRE 16 -1 (-5200 2350)(-4875 2350);
WIRE 16 -1 (-5200 2400)(-4875 2400);
WIRE 16 -1 (-5200 2450)(-4875 2450);
WIRE 16 -1 (-5200 2500)(-4875 2500);
WIRE 16 -1 (-5200 2550)(-4875 2550);
WIRE 16 -1 (-2975 1600)(-3275 1600);
WIRE 16 -1 (-2975 1650)(-3275 1650);
WIRE 16 -1 (-2975 1700)(-3275 1700);
WIRE 16 -1 (-2975 1750)(-3275 1750);
WIRE 16 -1 (-3275 1800)(-2975 1800);
WIRE 16 -1 (-2975 1850)(-3275 1850);
WIRE 16 -1 (-3275 1900)(-2975 1900);
WIRE 16 -1 (-2975 1950)(-3275 1950);
WIRE 16 -1 (-2975 2000)(-3275 2000);
WIRE 16 -1 (-2975 2650)(-3275 2650);
WIRE 16 -1 (-2975 2700)(-3275 2700);
WIRE 16 -1 (-3275 2750)(-2975 2750);
WIRE 16 -1 (-2975 2800)(-3275 2800);
WIRE 16 -1 (-2975 2850)(-3275 2850);
WIRE 16 -1 (-2975 2900)(-3275 2900);
WIRE 16 -1 (-2975 2950)(-3275 2950);
WIRE 16 -1 (-2975 3000)(-3275 3000);
WIRE 16 -1 (-3275 3050)(-2975 3050);
WIRE 16 -1 (-2975 3100)(-3275 3100);
WIRE 16 -1 (-2975 3150)(-3275 3150);
WIRE 16 -1 (-2975 3200)(-3275 3200);
WIRE 16 -1 (-2975 3300)(-3275 3300);
WIRE 16 -1 (-3275 3350)(-2975 3350);
WIRE 16 -1 (-3275 3400)(-2975 3400);
WIRE 16 -1 (-2975 3450)(-3275 3450);
WIRE 16 -1 (-2975 3500)(-3275 3500);
WIRE 16 -1 (-2975 3550)(-3275 3550);
WIRE 16 -1 (-2975 3600)(-3275 3600);
WIRE 16 -1 (-2975 2050)(-3275 2050);
WIRE 16 -1 (-2975 2100)(-3275 2100);
WIRE 16 -1 (-3275 2150)(-2975 2150);
WIRE 16 -1 (-3275 2200)(-2975 2200);
WIRE 16 -1 (-2975 2250)(-3275 2250);
WIRE 16 -1 (-2975 2300)(-3275 2300);
WIRE 16 -1 (-2975 2350)(-3275 2350);
WIRE 16 -1 (-2975 2400)(-3275 2400);
WIRE 16 -1 (-2975 2450)(-3275 2450);
WIRE 16 -1 (-2975 2500)(-3275 2500);
WIRE 16 -1 (-2975 2550)(-3275 2550);
FORCENOTE
SKYLAKE - SKT0 - 13 OF 21
(-1650 150) 0;
DISPLAY LEFT (-1650 150);
DISPLAY 1.021277 (-1650 150);
PAINT RED (-1650 150);
FORCENOTE
BOM_COST=PROC_SOCKET
(-7925 200) 0;
DISPLAY LEFT (-7925 200);
DISPLAY 1.723404 (-7925 200);
PAINT PURPLE (-7925 200);
FORCENOTE
ROOM=CPU0
(-7925 325) 0;
DISPLAY LEFT (-7925 325);
DISPLAY 1.723404 (-7925 325);
PAINT PURPLE (-7925 325);
QUIT
